G04 ================== begin FILE IDENTIFICATION RECORD ==================*
G04 Layout Name:  t6mg_pdb_a_v02_0109_1330.brd*
G04 Film Name:    smt.art*
G04 File Format:  Gerber RS274X*
G04 File Origin:  Cadence Allegro 16.3-S038*
G04 Origin Date:  Mon Jan 13 14:11:51 2014*
G04 *
G04 Layer:  DRAWING FORMAT/TITLE_BLOCK*
G04 Layer:  VIA CLASS/SOLDERMASK_TOP*
G04 Layer:  PIN/SOLDERMASK_TOP*
G04 Layer:  PACKAGE GEOMETRY/SOLDERMASK_TOP*
G04 Layer:  MANUFACTURING/PHOTOPLOT_OUTLINE*
G04 Layer:  DRAWING FORMAT/TITLE_DATA_SMT*
G04 Layer:  BOARD GEOMETRY/SOLDERMASK_TOP*
G04 *
G04 Offset:    (0.00 0.00)*
G04 Mirror:    No*
G04 Mode:      Positive*
G04 Rotation:  0*
G04 FullContactRelief:  No*
G04 UndefLineWidth:     6.00*
G04 ================== end FILE IDENTIFICATION RECORD ====================*
%FSLAX25Y25*MOIN*%
%IR0*IPPOS*OFA0.00000B0.00000*MIA0B0*SFA1.00000B1.00000*%
%ADD39C,.05*%
%ADD23C,.034*%
%ADD16C,.044*%
%ADD21C,.072*%
%ADD20C,.081*%
%ADD14C,.056*%
%ADD38R,.05X.05*%
%ADD11C,.067*%
%ADD35C,.068*%
%ADD25C,.059*%
%ADD18R,.044X.044*%
%ADD24R,.081X.081*%
%ADD22C,.097*%
%ADD28R,.056X.056*%
%ADD12R,.067X.067*%
%ADD36R,.068X.068*%
%ADD26R,.059X.059*%
%ADD13R,.024X.022*%
%ADD19R,.022X.024*%
%ADD42O,.225X.264*%
%ADD34R,.036X.032*%
%ADD40R,.032X.036*%
%ADD17C,.115*%
%ADD29R,.072X.026*%
%ADD10C,.152*%
%ADD41C,.225*%
%ADD33R,.026X.072*%
%ADD30C,.118*%
%ADD43C,.335*%
%ADD37C,.119*%
%ADD15C,.146*%
%ADD31R,.054X.039*%
%ADD27C,.178*%
%ADD32R,.048X.058*%
%ADD44C,.02*%
%ADD45C,.006*%
%ADD46C,.194*%
G75*
%LPD*%
G75*
G36*
G01X65354Y95060D02*
G02I0J19900D01*
G37*
G36*
G01Y445060D02*
G02I0J19900D01*
G37*
G36*
G01Y795060D02*
G02I0J19900D01*
G37*
G36*
G01Y1145060D02*
G02I0J19900D01*
G37*
G36*
G01Y1495060D02*
G02I0J19900D01*
G37*
G36*
G01Y1845060D02*
G02I0J19900D01*
G37*
G36*
G01X62237Y878761D02*
G03I-5900J0D01*
G37*
G36*
G01X326986Y127165D02*
G02I-19900J0D01*
G37*
G36*
G01Y477165D02*
G02I-19900J0D01*
G37*
G36*
G01Y827165D02*
G02I-19900J0D01*
G37*
G36*
G01Y1343504D02*
G02I-19900J0D01*
G37*
G36*
G01Y1693504D02*
G02I-19900J0D01*
G37*
G36*
G01X326987Y2043503D02*
G02I-19900J0D01*
G37*
G36*
G01X394491Y62106D02*
G03I-5900J0D01*
G37*
G36*
G01X391516Y1991570D02*
G03I-5900J0D01*
G37*
%LPC*%
G75*
G54D46*
X65354Y114960D03*
Y464960D03*
Y814960D03*
Y1164960D03*
Y1514960D03*
Y1864960D03*
X307086Y127165D03*
Y477165D03*
Y827165D03*
Y1343504D03*
Y1693504D03*
X307087Y2043503D03*
%LPD*%
G75*
G54D10*
X29979Y30500D03*
Y75500D03*
Y166500D03*
Y211500D03*
Y239500D03*
Y284500D03*
Y375500D03*
Y420500D03*
G54D11*
X22756Y113818D03*
X22480Y316838D03*
Y328649D03*
X22756Y1866819D03*
Y1948818D03*
Y2023818D03*
G54D20*
X23402Y1668874D03*
Y1685410D03*
Y1701945D03*
Y1718480D03*
Y1735016D03*
Y1751551D03*
Y1768087D03*
Y1784622D03*
Y1817693D03*
Y1801158D03*
X45056Y1668874D03*
Y1685410D03*
Y1701945D03*
Y1718480D03*
Y1735016D03*
Y1751551D03*
Y1768087D03*
Y1784622D03*
Y1801158D03*
G54D30*
X56337Y878761D03*
X388591Y62106D03*
X385616Y1991570D03*
G54D12*
X22756Y125629D03*
X22480Y340460D03*
X22756Y1878630D03*
Y1960629D03*
Y2035629D03*
G54D21*
X30473Y102007D03*
Y137440D03*
X30197Y305027D03*
Y352271D03*
X30473Y1855008D03*
Y1890441D03*
Y1937007D03*
Y1972440D03*
Y2012007D03*
Y2047440D03*
G54D31*
X74602Y1333203D03*
Y1328203D03*
Y1323203D03*
Y1318203D03*
X54130D03*
Y1323203D03*
Y1328203D03*
Y1333203D03*
G54D40*
X271547Y250964D03*
Y256764D03*
X281569Y426540D03*
Y432340D03*
X285348Y601162D03*
Y606962D03*
X273114Y776236D03*
Y782036D03*
X285966Y949961D03*
Y955761D03*
X282958Y1124951D03*
Y1130751D03*
X283808Y1299622D03*
Y1305422D03*
X270234Y1473162D03*
Y1478962D03*
X284086Y1649843D03*
Y1655643D03*
X281066Y1824071D03*
Y1829871D03*
X294483Y72918D03*
Y78718D03*
X314562Y1998607D03*
Y2004407D03*
G54D13*
X13441Y501915D03*
Y498765D03*
X10914Y576211D03*
Y573061D03*
X15984Y576277D03*
Y573127D03*
X11153Y1635435D03*
Y1632285D03*
X16552Y1635303D03*
Y1632153D03*
X58752Y1302746D03*
Y1299596D03*
X50331Y1302680D03*
Y1299530D03*
X71909Y1302580D03*
Y1299430D03*
X67568Y1302581D03*
Y1299431D03*
X63061Y1302746D03*
Y1299596D03*
X54543Y1302681D03*
Y1299531D03*
X52227Y1341972D03*
Y1338822D03*
X88681Y701593D03*
Y698443D03*
X92860D03*
Y701593D03*
X80269D03*
Y698443D03*
X84533D03*
Y701593D03*
X84417Y1754902D03*
Y1758052D03*
X88624D03*
Y1754902D03*
X80349D03*
Y1758052D03*
X107268Y78205D03*
X107263Y75055D03*
Y78205D03*
X107268Y81355D03*
X107668Y429254D03*
Y426104D03*
Y422954D03*
Y426104D03*
X107615Y777299D03*
Y774149D03*
X107617Y771001D03*
Y774151D03*
X108819Y1119015D03*
X108816Y1125313D03*
Y1122163D03*
X108819Y1122165D03*
X108573Y1473357D03*
Y1470207D03*
X108574Y1467057D03*
Y1470207D03*
X108819Y1818228D03*
Y1815078D03*
Y1818228D03*
Y1821378D03*
X155370Y91281D03*
Y88131D03*
X155366Y85017D03*
Y88167D03*
X156321Y418198D03*
Y415048D03*
X161256Y418195D03*
Y415045D03*
X155351Y439268D03*
Y436118D03*
X155348Y432969D03*
Y436119D03*
X155356Y780982D03*
X155362Y787280D03*
Y784130D03*
X155356Y784132D03*
X156117Y1116127D03*
Y1112977D03*
X160870Y1116135D03*
Y1112985D03*
X155264Y1135344D03*
Y1132194D03*
X155263Y1129045D03*
Y1132195D03*
X155834Y1480274D03*
X155816Y1477124D03*
Y1480274D03*
X155834Y1483424D03*
X155570Y1831380D03*
Y1828230D03*
X155561Y1825087D03*
Y1828237D03*
X263086Y151264D03*
X267420D03*
X263086Y154414D03*
X267420D03*
X264516Y500919D03*
Y504069D03*
X264181Y851243D03*
Y854393D03*
X267194Y1195314D03*
Y1198464D03*
X262559Y1195314D03*
Y1198464D03*
X271943Y151264D03*
X276523D03*
X271943Y154414D03*
X276523D03*
X276617Y253439D03*
Y250289D03*
X281193Y253439D03*
Y250289D03*
X281074Y326517D03*
Y329667D03*
X289895Y326517D03*
Y329667D03*
X285513Y326517D03*
Y329667D03*
X291002Y429015D03*
Y425865D03*
X286665Y429015D03*
Y425865D03*
X273405Y500919D03*
Y504069D03*
X268938Y500919D03*
Y504069D03*
X277776Y500919D03*
Y504069D03*
X290984Y603637D03*
Y600487D03*
X283340Y676124D03*
Y679274D03*
X278955Y676124D03*
Y679274D03*
X274514Y676124D03*
Y679274D03*
X270109Y676124D03*
Y679274D03*
X278184Y778711D03*
Y775561D03*
X282737Y778711D03*
Y775561D03*
X277788Y851243D03*
X273305D03*
X268686D03*
X277788Y854393D03*
X273305D03*
X268686D03*
X291194Y949286D03*
Y952436D03*
X290107Y1019882D03*
X285666D03*
X281124D03*
X290107Y1023032D03*
X285666D03*
X281124D03*
X288188Y1127426D03*
Y1124276D03*
X276807Y1195314D03*
Y1198464D03*
X272082Y1195314D03*
Y1198464D03*
X289210Y1302097D03*
Y1298947D03*
X284240Y1378342D03*
Y1381492D03*
X279518Y1378341D03*
Y1381491D03*
X275052Y1378341D03*
Y1381491D03*
X270579Y1378341D03*
Y1381491D03*
X275521Y1475637D03*
Y1472487D03*
X279990Y1475637D03*
Y1472487D03*
X291054Y1547451D03*
Y1550601D03*
X289421Y1649168D03*
Y1652318D03*
X289499Y1726915D03*
Y1730065D03*
X284583Y1726915D03*
Y1730065D03*
X274704Y1726915D03*
Y1730065D03*
X279703Y1726915D03*
Y1730065D03*
X286623Y1826546D03*
Y1823396D03*
X291550Y1826546D03*
Y1823396D03*
X287121Y1901895D03*
Y1905045D03*
X282717Y1901895D03*
Y1905045D03*
X278262Y1901895D03*
Y1905045D03*
X273817Y1901895D03*
Y1905045D03*
X304151Y75393D03*
Y72243D03*
X308651Y75393D03*
Y72243D03*
X313089Y75393D03*
Y72243D03*
X299687Y75393D03*
Y72243D03*
X294506Y326517D03*
Y329667D03*
X295509Y603637D03*
Y600487D03*
X295874Y949286D03*
Y952436D03*
X294617Y1019882D03*
Y1023032D03*
X292698Y1127426D03*
Y1124276D03*
X294133Y1302097D03*
Y1298947D03*
X304870Y1547451D03*
Y1550601D03*
X295675Y1547451D03*
Y1550601D03*
X300392Y1547451D03*
Y1550601D03*
X294090Y1649168D03*
Y1652318D03*
X317567Y75393D03*
Y72243D03*
X322005Y75393D03*
Y72243D03*
X320045Y2002031D03*
Y1998881D03*
X324803Y2002031D03*
Y1998881D03*
G54D22*
X45411Y505996D03*
Y568004D03*
Y1564000D03*
Y1626008D03*
G54D32*
X60289Y1770835D03*
X67769D03*
X60289Y1762982D03*
X67769D03*
X60289Y1755171D03*
X67769D03*
X89071Y1748227D03*
X81591D03*
X87057Y1764190D03*
X79577D03*
G54D41*
X307086Y308267D03*
G54D14*
X14073Y512197D03*
Y522000D03*
Y552000D03*
Y561803D03*
Y1580004D03*
Y1570201D03*
Y1610004D03*
Y1619807D03*
X65254Y519500D03*
Y529500D03*
Y539500D03*
X55254Y524500D03*
Y534500D03*
X65254Y549500D03*
X55254Y544500D03*
X65254Y1577504D03*
Y1587504D03*
Y1597504D03*
X55254Y1582504D03*
Y1592504D03*
Y1602504D03*
X65254Y1607504D03*
G54D23*
X45789Y896341D03*
X46023Y904215D03*
X48085Y919992D03*
X45981Y911910D03*
X47835Y960098D03*
X47109Y975598D03*
X48203Y1022325D03*
X47474Y1061692D03*
X47833Y1085626D03*
X47665Y1075692D03*
X47414Y1114586D03*
X47540Y1136770D03*
X46992Y1129235D03*
X47077Y1121658D03*
X46320Y1215867D03*
X49856Y1208711D03*
X45815Y1202354D03*
X46566Y1194825D03*
X46404Y1231610D03*
X45718Y1242795D03*
X49936Y1311343D03*
X65354Y101180D03*
X55511Y105117D03*
X51574Y114960D03*
X55511Y124803D03*
X65354Y128740D03*
Y451180D03*
X55511Y455117D03*
X51574Y464960D03*
X55511Y474803D03*
X65354Y478740D03*
Y801180D03*
X55511Y805117D03*
X51574Y814960D03*
X55511Y824803D03*
X65354Y828740D03*
X51149Y967593D03*
X51960Y953195D03*
X65354Y1151180D03*
X55511Y1155117D03*
X51574Y1164960D03*
X55511Y1174803D03*
X65354Y1178740D03*
X55496Y1235735D03*
X54654Y1244744D03*
X65354Y1501180D03*
X55511Y1505117D03*
X51574Y1514960D03*
X55511Y1524803D03*
X65354Y1528740D03*
X64356Y1788075D03*
X65354Y1851180D03*
X55511Y1855117D03*
X51574Y1864960D03*
X55511Y1874803D03*
X65354Y1878740D03*
X75197Y105117D03*
Y124803D03*
X79134Y114960D03*
Y464960D03*
X75197Y455117D03*
Y474803D03*
X93165Y706331D03*
X75197Y805117D03*
Y824803D03*
X79134Y814960D03*
Y1164960D03*
X75197Y1155117D03*
Y1174803D03*
X81341Y1310698D03*
X75197Y1505117D03*
Y1524803D03*
X79134Y1514960D03*
X75198Y1750574D03*
X92026Y1774879D03*
X79134Y1864960D03*
X75197Y1855117D03*
Y1874803D03*
X100595Y690710D03*
X307086Y113385D03*
X297243Y117322D03*
X293306Y127165D03*
X297243Y137008D03*
X307086Y140945D03*
Y463385D03*
X297243Y467322D03*
X293306Y477165D03*
X297243Y487008D03*
X307086Y490945D03*
Y813385D03*
X297243Y817322D03*
X293306Y827165D03*
X297243Y837008D03*
X307086Y840945D03*
Y1329724D03*
X297243Y1333661D03*
X293306Y1343504D03*
X297243Y1353347D03*
X307086Y1357284D03*
Y1679724D03*
X297243Y1683661D03*
X293306Y1693504D03*
X297243Y1703347D03*
X307086Y1707284D03*
X307087Y2029723D03*
X297244Y2033660D03*
X293307Y2043503D03*
X297244Y2053346D03*
X307087Y2057283D03*
X320866Y127165D03*
X316929Y117322D03*
Y137008D03*
Y467322D03*
Y487008D03*
X320866Y477165D03*
Y827165D03*
X316929Y817322D03*
Y837008D03*
Y1333661D03*
Y1353347D03*
X320866Y1343504D03*
Y1693504D03*
X316929Y1683661D03*
Y1703347D03*
X316930Y2033660D03*
Y2053346D03*
X320867Y2043503D03*
G54D15*
X30254Y514500D03*
Y559500D03*
Y1572504D03*
Y1617504D03*
G54D33*
X70376Y1780543D03*
Y1801343D03*
X85376Y1780543D03*
X80376D03*
X75376D03*
Y1801343D03*
X80376D03*
X85376D03*
G54D42*
X307086Y1883071D03*
G54D24*
X45056Y1817693D03*
G54D43*
X359842Y78780D03*
Y253780D03*
Y428779D03*
Y603779D03*
Y778780D03*
Y953780D03*
Y1128779D03*
Y1303780D03*
Y1478780D03*
Y1653780D03*
Y1828779D03*
Y2003780D03*
G54D34*
X87363Y708496D03*
X81563D03*
G54D25*
X64979Y35500D03*
Y45500D03*
Y55500D03*
X54979Y40500D03*
Y50500D03*
X64979Y65500D03*
X54979Y60500D03*
X64979Y171500D03*
X54979Y176500D03*
X64979Y181500D03*
Y191500D03*
Y201500D03*
X54979Y186500D03*
Y196500D03*
X64979Y244500D03*
X54979Y249500D03*
X64979Y254500D03*
Y264500D03*
Y274500D03*
X54979Y259500D03*
Y269500D03*
X64979Y380500D03*
Y390500D03*
X54979Y385500D03*
Y395500D03*
X64979Y400500D03*
Y410500D03*
X54979Y405500D03*
X189762Y73105D03*
X190289Y152050D03*
X190357Y247568D03*
X190817Y331786D03*
X189761Y421732D03*
X190553Y506517D03*
X192888Y598130D03*
X190816Y681645D03*
X191846Y774526D03*
X191606Y856244D03*
X196311Y947202D03*
X195516Y1032544D03*
X191250Y1122856D03*
X191342Y1206233D03*
X191846Y1299104D03*
X190552Y1380966D03*
X189463Y1474162D03*
X191079Y1557277D03*
X192143Y1648177D03*
X191607Y1731351D03*
X191530Y1823227D03*
X190289Y1900420D03*
X192125Y1998730D03*
X191530Y2043388D03*
G54D16*
X15547Y707364D03*
X25389D03*
X7673Y703427D03*
X15547Y715238D03*
Y723112D03*
Y730986D03*
X25389Y715238D03*
Y723112D03*
Y730986D03*
X7673Y711301D03*
Y719175D03*
Y727049D03*
X15547Y738860D03*
Y746734D03*
Y754608D03*
X25389Y738860D03*
Y746734D03*
Y754608D03*
X7673Y734923D03*
Y742797D03*
Y750671D03*
Y758545D03*
X15547Y762483D03*
Y770357D03*
Y778231D03*
X25389Y762483D03*
Y770357D03*
Y778231D03*
X7673Y766419D03*
Y774293D03*
Y782167D03*
X15547Y786105D03*
Y793979D03*
Y801853D03*
X25389Y786105D03*
Y793979D03*
Y801853D03*
X7673Y790041D03*
Y797915D03*
Y805790D03*
X15547Y809727D03*
Y817601D03*
Y825475D03*
X25389Y809727D03*
Y817601D03*
Y825475D03*
X7673Y813664D03*
Y821538D03*
Y829412D03*
X15547Y833349D03*
Y841223D03*
Y849097D03*
X25389Y833349D03*
Y841223D03*
Y849097D03*
X7673Y837286D03*
Y845160D03*
Y853034D03*
X15547Y856971D03*
Y864845D03*
Y872719D03*
X25389Y856971D03*
Y864845D03*
Y872719D03*
X7673Y860908D03*
Y868782D03*
Y876656D03*
X15547Y880593D03*
Y888467D03*
Y896341D03*
X25389Y880593D03*
Y888467D03*
Y896341D03*
X7673Y884530D03*
Y892404D03*
Y900278D03*
X15547Y904215D03*
Y912089D03*
Y919963D03*
X25389Y904215D03*
Y912089D03*
Y919963D03*
X7673Y908152D03*
Y916026D03*
Y923900D03*
X15547Y927837D03*
Y935711D03*
Y943585D03*
Y951459D03*
X25389Y927837D03*
Y935711D03*
Y943585D03*
Y951459D03*
X7673Y931774D03*
Y939648D03*
Y947522D03*
X15547Y959333D03*
Y967207D03*
Y975081D03*
X25389Y959333D03*
Y967207D03*
Y975081D03*
X7673Y955396D03*
Y963270D03*
Y971144D03*
Y979018D03*
Y994766D03*
X15547Y990829D03*
Y998703D03*
X25389Y990829D03*
Y998703D03*
X7673Y1002640D03*
Y1010514D03*
Y1018388D03*
X15547Y1006577D03*
Y1014451D03*
Y1022325D03*
X25389Y1006577D03*
Y1014451D03*
Y1022325D03*
X7673Y1026262D03*
X15547Y1030199D03*
X15551Y1065629D03*
X25393D03*
X7677Y1061692D03*
Y1069566D03*
X15551Y1073503D03*
Y1081377D03*
Y1089251D03*
X25393Y1073503D03*
Y1081377D03*
Y1089251D03*
X7677Y1077440D03*
Y1085314D03*
Y1093188D03*
X15551Y1097125D03*
Y1104999D03*
Y1112873D03*
Y1120748D03*
X25393Y1097125D03*
Y1104999D03*
Y1112873D03*
Y1120748D03*
X7677Y1101062D03*
Y1108936D03*
Y1116810D03*
X15551Y1128622D03*
Y1136496D03*
Y1144370D03*
X25393Y1128622D03*
Y1136496D03*
Y1144370D03*
X7677Y1124684D03*
Y1132558D03*
Y1140432D03*
X15551Y1152244D03*
Y1160118D03*
Y1167992D03*
X25393Y1152244D03*
Y1160118D03*
Y1167992D03*
X7677Y1148306D03*
Y1156180D03*
Y1164055D03*
X15551Y1175866D03*
Y1183740D03*
Y1191614D03*
X25393Y1175866D03*
Y1183740D03*
Y1191614D03*
X7677Y1171929D03*
Y1179803D03*
Y1187677D03*
X15551Y1199488D03*
Y1207362D03*
Y1215236D03*
X25393Y1199488D03*
Y1207362D03*
Y1215236D03*
X7677Y1195551D03*
Y1203425D03*
Y1211299D03*
X15551Y1223110D03*
Y1230984D03*
Y1238858D03*
X25393Y1223110D03*
Y1230984D03*
Y1238858D03*
X7677Y1219173D03*
Y1227047D03*
Y1234921D03*
X15551Y1246732D03*
Y1254606D03*
Y1262480D03*
X25393Y1246732D03*
Y1254606D03*
Y1262480D03*
X7677Y1242795D03*
Y1250669D03*
Y1258543D03*
X15551Y1270354D03*
Y1278228D03*
Y1286102D03*
X25393Y1270354D03*
Y1278228D03*
Y1286102D03*
X7677Y1266417D03*
Y1274291D03*
Y1282165D03*
X15551Y1293976D03*
Y1301850D03*
Y1309724D03*
X25393Y1293976D03*
Y1301850D03*
Y1309724D03*
X7677Y1290039D03*
Y1297913D03*
Y1305787D03*
Y1313661D03*
X15551Y1317598D03*
Y1325472D03*
Y1333346D03*
X25393Y1317598D03*
Y1325472D03*
Y1333346D03*
X7677Y1321535D03*
Y1329409D03*
Y1337283D03*
Y1353031D03*
Y1360905D03*
X15551Y1349094D03*
Y1356968D03*
X25393Y1349094D03*
Y1356968D03*
X7677Y1368779D03*
Y1376653D03*
Y1384527D03*
X15551Y1364842D03*
Y1372716D03*
Y1380590D03*
X25393Y1364842D03*
Y1372716D03*
Y1380590D03*
X15551Y1388464D03*
X33263Y703427D03*
Y711301D03*
Y719175D03*
Y727049D03*
Y734923D03*
Y742797D03*
Y750671D03*
Y758545D03*
Y766419D03*
Y774293D03*
Y782167D03*
Y790041D03*
Y797915D03*
Y805790D03*
Y813664D03*
Y821538D03*
Y829412D03*
Y837286D03*
Y845160D03*
Y853034D03*
Y860908D03*
Y868782D03*
Y876656D03*
Y884530D03*
Y892404D03*
Y900278D03*
Y908152D03*
Y916026D03*
Y923900D03*
Y931774D03*
Y939648D03*
Y947522D03*
Y955396D03*
Y963270D03*
Y971144D03*
Y979018D03*
Y994766D03*
Y1002640D03*
Y1010514D03*
Y1018388D03*
Y1026262D03*
X33267Y1061692D03*
Y1069566D03*
Y1077440D03*
Y1085314D03*
Y1093188D03*
Y1101062D03*
Y1108936D03*
Y1116810D03*
Y1124684D03*
Y1132558D03*
Y1140432D03*
Y1148306D03*
Y1156180D03*
Y1164055D03*
Y1171929D03*
Y1179803D03*
Y1187677D03*
Y1195551D03*
Y1203425D03*
Y1211299D03*
Y1219173D03*
Y1227047D03*
Y1234921D03*
Y1242795D03*
Y1250669D03*
Y1258543D03*
Y1266417D03*
Y1274291D03*
Y1282165D03*
Y1290039D03*
Y1297913D03*
Y1305787D03*
Y1313661D03*
Y1321535D03*
Y1329409D03*
Y1337283D03*
Y1353031D03*
Y1360905D03*
Y1368779D03*
Y1376653D03*
Y1384527D03*
G54D44*
G01X104331Y0D02*
X397638D01*
G03X405512Y7874I0J7874D01*
G01Y2078740D01*
G03X397638Y2086614I-7874J0D01*
G01X104331D01*
G03X98425Y2080709I0J-5906D01*
G01Y2076772D01*
G02X92520Y2070866I-5905J-1D01*
G01X5906D01*
G03X0Y2064961I-1J-5905D01*
G01Y21654D01*
G03X5906Y15748I5906J0D01*
G01X92520D01*
G02X98425Y9843I0J-5905D01*
G01Y5906D01*
G03X104331Y0I5906J0D01*
G54D17*
X20468Y696341D03*
Y984333D03*
X20472Y1054606D03*
Y1342598D03*
G54D26*
X54979Y70500D03*
Y206500D03*
Y279500D03*
Y415500D03*
X203542Y73105D03*
X204069Y152050D03*
X204137Y247568D03*
X204597Y331786D03*
X203541Y421732D03*
X204333Y506517D03*
X206668Y598130D03*
X204596Y681645D03*
X205626Y774526D03*
X205386Y856244D03*
X210091Y947202D03*
X209296Y1032544D03*
X205030Y1122856D03*
X205122Y1206233D03*
X205626Y1299104D03*
X204332Y1380966D03*
X203243Y1474162D03*
X204859Y1557277D03*
X205923Y1648177D03*
X205387Y1731351D03*
X205310Y1823227D03*
X204069Y1900420D03*
X205905Y1998730D03*
X205310Y2043388D03*
G54D35*
X119920Y18071D03*
Y28071D03*
Y38071D03*
Y48071D03*
Y58071D03*
Y68071D03*
Y78071D03*
Y88071D03*
Y98071D03*
Y108071D03*
Y118071D03*
Y128071D03*
Y138071D03*
Y148071D03*
Y158071D03*
Y168071D03*
Y178071D03*
Y188071D03*
Y198071D03*
Y208071D03*
Y218071D03*
Y228071D03*
Y238071D03*
Y248071D03*
Y258071D03*
Y268071D03*
Y278071D03*
Y288071D03*
Y298071D03*
Y308071D03*
Y318071D03*
Y366102D03*
Y376102D03*
Y386102D03*
Y396102D03*
Y406102D03*
Y416102D03*
Y426102D03*
Y436102D03*
Y446102D03*
Y456102D03*
Y466102D03*
Y476102D03*
Y486102D03*
Y496102D03*
Y506102D03*
Y516102D03*
Y526102D03*
Y536102D03*
Y546102D03*
Y556102D03*
Y566102D03*
Y576102D03*
Y586102D03*
Y596102D03*
Y606102D03*
Y616102D03*
Y626102D03*
Y636102D03*
Y646102D03*
Y656102D03*
Y666102D03*
Y714134D03*
Y724134D03*
Y734134D03*
Y744134D03*
Y754134D03*
Y764134D03*
Y774134D03*
Y784134D03*
Y794134D03*
Y804134D03*
Y814134D03*
Y824134D03*
Y834134D03*
Y844134D03*
Y854134D03*
Y864134D03*
Y874134D03*
Y884134D03*
Y894134D03*
Y904134D03*
Y914134D03*
Y924134D03*
Y934134D03*
Y944134D03*
Y954134D03*
Y964134D03*
Y974134D03*
Y984134D03*
Y994134D03*
Y1004134D03*
Y1014134D03*
Y1062165D03*
Y1072165D03*
Y1082165D03*
Y1092165D03*
Y1102165D03*
Y1112165D03*
Y1122165D03*
Y1132165D03*
Y1142165D03*
Y1152165D03*
Y1162165D03*
Y1172165D03*
Y1182165D03*
Y1192165D03*
Y1202165D03*
Y1212165D03*
Y1222165D03*
Y1232165D03*
Y1242165D03*
Y1252165D03*
Y1262165D03*
Y1272165D03*
Y1282165D03*
Y1292165D03*
Y1302165D03*
Y1312165D03*
Y1322165D03*
Y1332165D03*
Y1342165D03*
Y1352165D03*
Y1362165D03*
Y1410197D03*
Y1420197D03*
Y1430197D03*
Y1440197D03*
Y1450197D03*
Y1460197D03*
Y1470197D03*
Y1480197D03*
Y1490197D03*
Y1500197D03*
Y1510197D03*
Y1520197D03*
Y1530197D03*
Y1540197D03*
Y1550197D03*
Y1560197D03*
Y1570197D03*
Y1580197D03*
Y1590197D03*
Y1600197D03*
Y1610197D03*
Y1620197D03*
Y1630197D03*
Y1640197D03*
Y1650197D03*
Y1660197D03*
Y1670197D03*
Y1680197D03*
Y1690197D03*
Y1700197D03*
Y1710197D03*
Y1758228D03*
Y1768228D03*
Y1778228D03*
Y1788228D03*
Y1798228D03*
Y1808228D03*
Y1818228D03*
Y1828228D03*
Y1838228D03*
Y1848228D03*
Y1858228D03*
Y1868228D03*
Y1878228D03*
Y1888228D03*
Y1898228D03*
Y1908228D03*
Y1918228D03*
Y1928228D03*
Y1938228D03*
Y1948228D03*
Y1958228D03*
Y1968228D03*
Y1978228D03*
Y1988228D03*
Y1998228D03*
Y2008228D03*
Y2018228D03*
Y2028228D03*
Y2038228D03*
Y2048228D03*
Y2058228D03*
X139920Y28071D03*
Y18071D03*
Y58071D03*
Y48071D03*
Y38071D03*
Y78071D03*
Y68071D03*
Y98071D03*
Y88071D03*
Y128071D03*
Y118071D03*
Y108071D03*
Y148071D03*
Y138071D03*
Y178071D03*
Y168071D03*
Y158071D03*
Y198071D03*
Y188071D03*
Y228071D03*
Y218071D03*
Y208071D03*
Y248071D03*
Y238071D03*
Y268071D03*
Y258071D03*
Y298071D03*
Y288071D03*
Y278071D03*
Y318071D03*
Y308071D03*
Y328071D03*
Y366102D03*
Y396102D03*
Y386102D03*
Y376102D03*
Y416102D03*
Y406102D03*
Y436102D03*
Y426102D03*
Y466102D03*
Y456102D03*
Y446102D03*
Y486102D03*
Y476102D03*
Y516102D03*
Y506102D03*
Y496102D03*
Y536102D03*
Y526102D03*
Y566102D03*
Y556102D03*
Y546102D03*
Y586102D03*
Y576102D03*
Y606102D03*
Y596102D03*
Y636102D03*
Y626102D03*
Y616102D03*
Y656102D03*
Y646102D03*
Y676102D03*
Y666102D03*
Y734134D03*
Y724134D03*
Y714134D03*
Y754134D03*
Y744134D03*
Y774134D03*
Y764134D03*
Y804134D03*
Y794134D03*
Y784134D03*
Y824134D03*
Y814134D03*
Y854134D03*
Y844134D03*
Y834134D03*
Y874134D03*
Y864134D03*
Y904134D03*
Y894134D03*
Y884134D03*
Y924134D03*
Y914134D03*
Y944134D03*
Y934134D03*
Y974134D03*
Y964134D03*
Y954134D03*
Y994134D03*
Y984134D03*
Y1024134D03*
Y1014134D03*
Y1004134D03*
Y1072165D03*
Y1062165D03*
Y1092165D03*
Y1082165D03*
Y1122165D03*
Y1112165D03*
Y1102165D03*
Y1142165D03*
Y1132165D03*
Y1162165D03*
Y1152165D03*
Y1192165D03*
Y1182165D03*
Y1172165D03*
Y1212165D03*
Y1202165D03*
Y1242165D03*
Y1232165D03*
Y1222165D03*
Y1262165D03*
Y1252165D03*
Y1282165D03*
Y1272165D03*
Y1312165D03*
Y1302165D03*
Y1292165D03*
Y1332165D03*
Y1322165D03*
Y1362165D03*
Y1352165D03*
Y1342165D03*
Y1372165D03*
Y1410197D03*
Y1430197D03*
Y1420197D03*
Y1460197D03*
Y1450197D03*
Y1440197D03*
Y1480197D03*
Y1470197D03*
Y1500197D03*
Y1490197D03*
Y1530197D03*
Y1520197D03*
Y1510197D03*
Y1550197D03*
Y1540197D03*
Y1580197D03*
Y1570197D03*
Y1560197D03*
Y1600197D03*
Y1590197D03*
Y1620197D03*
Y1610197D03*
Y1650197D03*
Y1640197D03*
Y1630197D03*
Y1670197D03*
Y1660197D03*
Y1700197D03*
Y1690197D03*
Y1680197D03*
Y1720197D03*
Y1710197D03*
Y1768228D03*
Y1758228D03*
Y1798228D03*
Y1788228D03*
Y1778228D03*
Y1818228D03*
Y1808228D03*
Y1838228D03*
Y1828228D03*
Y1868228D03*
Y1858228D03*
Y1848228D03*
Y1888228D03*
Y1878228D03*
Y1918228D03*
Y1908228D03*
Y1898228D03*
Y1938228D03*
Y1928228D03*
Y1958228D03*
Y1948228D03*
Y1988228D03*
Y1978228D03*
Y1968228D03*
Y2008228D03*
Y1998228D03*
Y2038228D03*
Y2028228D03*
Y2018228D03*
Y2058228D03*
Y2048228D03*
Y2068228D03*
G54D45*
G01X-723776Y2987387D02*
Y-376795D01*
Y-489221D01*
X1782976D01*
Y-376795D01*
Y2987387D01*
X-723776D01*
G01X-4000Y-62500D02*
Y-137500D01*
X496000D01*
Y-62500D01*
X-4000D01*
G01X8000Y-127500D02*
Y-132500D01*
G01X6543Y-127500D02*
X9457D01*
G01X14367Y-132500D02*
X11833D01*
Y-127500D01*
X14367D01*
G01X13353Y-129917D02*
X11833D01*
G01X16933Y-127500D02*
Y-132500D01*
X19467D01*
G01X23300Y-132667D02*
X23173Y-132583D01*
Y-132417D01*
X23300Y-132333D01*
X23427Y-132417D01*
Y-132583D01*
X23300Y-132667D01*
G01Y-130417D02*
X23173Y-130333D01*
Y-130167D01*
X23300Y-130083D01*
X23427Y-130167D01*
Y-130333D01*
X23300Y-130417D01*
G01X28083Y-134167D02*
X27450Y-133333D01*
X27133Y-132500D01*
Y-129167D01*
X27450Y-128333D01*
X28083Y-127500D01*
G01X33500D02*
X32993Y-127667D01*
X32613Y-128083D01*
X32360Y-128583D01*
X32170Y-129250D01*
X32107Y-130000D01*
X32170Y-130750D01*
X32360Y-131417D01*
X32613Y-131917D01*
X32993Y-132333D01*
X33500Y-132500D01*
X34007Y-132333D01*
X34387Y-131917D01*
X34640Y-131417D01*
X34830Y-130750D01*
X34893Y-130000D01*
X34830Y-129250D01*
X34640Y-128583D01*
X34387Y-128083D01*
X34007Y-127667D01*
X33500Y-127500D01*
G01X37207Y-131500D02*
X37587Y-132083D01*
X38093Y-132417D01*
X38663Y-132500D01*
X39170Y-132417D01*
X39677Y-132000D01*
X39993Y-131500D01*
X40057Y-131000D01*
X39930Y-130417D01*
X39487Y-130000D01*
X39043Y-129833D01*
X38473D01*
G01X39043D02*
X39423Y-129583D01*
X39740Y-129167D01*
X39867Y-128667D01*
X39740Y-128167D01*
X39423Y-127750D01*
X38853Y-127500D01*
X38283Y-127583D01*
X37713Y-127917D01*
G01X44017Y-134167D02*
X44650Y-133333D01*
X44967Y-132500D01*
Y-129167D01*
X44650Y-128333D01*
X44017Y-127500D01*
G01X47407Y-131500D02*
X47787Y-132083D01*
X48293Y-132417D01*
X48863Y-132500D01*
X49370Y-132417D01*
X49877Y-132000D01*
X50193Y-131500D01*
X50257Y-131000D01*
X50130Y-130417D01*
X49687Y-130000D01*
X49243Y-129833D01*
X48673D01*
G01X49243D02*
X49623Y-129583D01*
X49940Y-129167D01*
X50067Y-128667D01*
X49940Y-128167D01*
X49623Y-127750D01*
X49053Y-127500D01*
X48483Y-127583D01*
X47913Y-127917D01*
G01X52697Y-128333D02*
X53077Y-127833D01*
X53520Y-127583D01*
X54027Y-127500D01*
X54660Y-127667D01*
X55103Y-128083D01*
X55230Y-128583D01*
X55167Y-129083D01*
X54913Y-129500D01*
X53647Y-130333D01*
X53077Y-130917D01*
X52697Y-131750D01*
X52570Y-132500D01*
X55230D01*
G01X58873D02*
X59000Y-131417D01*
X59190Y-130500D01*
X59443Y-129667D01*
X59760Y-128750D01*
X60267Y-127500D01*
X57733D01*
G01X63277Y-130833D02*
X64923D01*
G01X67997Y-128333D02*
X68377Y-127833D01*
X68820Y-127583D01*
X69327Y-127500D01*
X69960Y-127667D01*
X70403Y-128083D01*
X70530Y-128583D01*
X70467Y-129083D01*
X70213Y-129500D01*
X68947Y-130333D01*
X68377Y-130917D01*
X67997Y-131750D01*
X67870Y-132500D01*
X70530D01*
G01X72907Y-131500D02*
X73287Y-132083D01*
X73793Y-132417D01*
X74363Y-132500D01*
X74870Y-132417D01*
X75377Y-132000D01*
X75693Y-131500D01*
X75757Y-131000D01*
X75630Y-130417D01*
X75187Y-130000D01*
X74743Y-129833D01*
X74173D01*
G01X74743D02*
X75123Y-129583D01*
X75440Y-129167D01*
X75567Y-128667D01*
X75440Y-128167D01*
X75123Y-127750D01*
X74553Y-127500D01*
X73983Y-127583D01*
X73413Y-127917D01*
G01X80160Y-132500D02*
Y-127500D01*
X77817Y-131083D01*
X80983D01*
G01X83107Y-131750D02*
X83487Y-132167D01*
X83930Y-132417D01*
X84500Y-132500D01*
X85070Y-132333D01*
X85513Y-132000D01*
X85830Y-131417D01*
X85893Y-130750D01*
X85767Y-130083D01*
X85450Y-129667D01*
X85007Y-129333D01*
X84563Y-129250D01*
X84120Y-129333D01*
X83550Y-129667D01*
X83740Y-127500D01*
X85450D01*
G01X93497Y-132500D02*
Y-127500D01*
X95903D01*
G01X95017Y-129917D02*
X93497D01*
G01X98217Y-132500D02*
X99800Y-127500D01*
X101383Y-132500D01*
G01X100813Y-130750D02*
X98787D01*
G01X103570Y-132500D02*
X106230Y-127500D01*
G01X103570D02*
X106230Y-132500D01*
G01X110000Y-132667D02*
X109873Y-132583D01*
Y-132417D01*
X110000Y-132333D01*
X110127Y-132417D01*
Y-132583D01*
X110000Y-132667D01*
G01Y-130417D02*
X109873Y-130333D01*
Y-130167D01*
X110000Y-130083D01*
X110127Y-130167D01*
Y-130333D01*
X110000Y-130417D01*
G01X114783Y-134167D02*
X114150Y-133333D01*
X113833Y-132500D01*
Y-129167D01*
X114150Y-128333D01*
X114783Y-127500D01*
G01X120200D02*
X119693Y-127667D01*
X119313Y-128083D01*
X119060Y-128583D01*
X118870Y-129250D01*
X118807Y-130000D01*
X118870Y-130750D01*
X119060Y-131417D01*
X119313Y-131917D01*
X119693Y-132333D01*
X120200Y-132500D01*
X120707Y-132333D01*
X121087Y-131917D01*
X121340Y-131417D01*
X121530Y-130750D01*
X121593Y-130000D01*
X121530Y-129250D01*
X121340Y-128583D01*
X121087Y-128083D01*
X120707Y-127667D01*
X120200Y-127500D01*
G01X123907Y-131500D02*
X124287Y-132083D01*
X124793Y-132417D01*
X125363Y-132500D01*
X125870Y-132417D01*
X126377Y-132000D01*
X126693Y-131500D01*
X126757Y-131000D01*
X126630Y-130417D01*
X126187Y-130000D01*
X125743Y-129833D01*
X125173D01*
G01X125743D02*
X126123Y-129583D01*
X126440Y-129167D01*
X126567Y-128667D01*
X126440Y-128167D01*
X126123Y-127750D01*
X125553Y-127500D01*
X124983Y-127583D01*
X124413Y-127917D01*
G01X130717Y-134167D02*
X131350Y-133333D01*
X131667Y-132500D01*
Y-129167D01*
X131350Y-128333D01*
X130717Y-127500D01*
G01X134107Y-131500D02*
X134487Y-132083D01*
X134993Y-132417D01*
X135563Y-132500D01*
X136070Y-132417D01*
X136577Y-132000D01*
X136893Y-131500D01*
X136957Y-131000D01*
X136830Y-130417D01*
X136387Y-130000D01*
X135943Y-129833D01*
X135373D01*
G01X135943D02*
X136323Y-129583D01*
X136640Y-129167D01*
X136767Y-128667D01*
X136640Y-128167D01*
X136323Y-127750D01*
X135753Y-127500D01*
X135183Y-127583D01*
X134613Y-127917D01*
G01X139523Y-131917D02*
X139967Y-132333D01*
X140473Y-132500D01*
X140980Y-132333D01*
X141423Y-131833D01*
X141740Y-131083D01*
X141867Y-130333D01*
Y-129417D01*
X141740Y-128667D01*
X141423Y-128000D01*
X141043Y-127667D01*
X140600Y-127500D01*
X140093Y-127667D01*
X139713Y-128000D01*
X139460Y-128500D01*
X139333Y-129167D01*
X139460Y-129750D01*
X139777Y-130333D01*
X140157Y-130667D01*
X140600Y-130750D01*
X141107Y-130583D01*
X141487Y-130167D01*
X141867Y-129417D01*
G01X145573Y-132500D02*
X145700Y-131417D01*
X145890Y-130500D01*
X146143Y-129667D01*
X146460Y-128750D01*
X146967Y-127500D01*
X144433D01*
G01X149977Y-130833D02*
X151623D01*
G01X154507Y-131500D02*
X154887Y-132083D01*
X155393Y-132417D01*
X155963Y-132500D01*
X156470Y-132417D01*
X156977Y-132000D01*
X157293Y-131500D01*
X157357Y-131000D01*
X157230Y-130417D01*
X156787Y-130000D01*
X156343Y-129833D01*
X155773D01*
G01X156343D02*
X156723Y-129583D01*
X157040Y-129167D01*
X157167Y-128667D01*
X157040Y-128167D01*
X156723Y-127750D01*
X156153Y-127500D01*
X155583Y-127583D01*
X155013Y-127917D01*
G01X159797Y-130417D02*
X160240Y-129833D01*
X160620Y-129500D01*
X161127Y-129333D01*
X161570Y-129500D01*
X161887Y-129833D01*
X162140Y-130333D01*
X162203Y-130917D01*
X162140Y-131417D01*
X161887Y-131917D01*
X161507Y-132333D01*
X161063Y-132500D01*
X160557Y-132333D01*
X160113Y-131833D01*
X159860Y-131083D01*
X159797Y-130250D01*
X159923Y-129167D01*
X160113Y-128583D01*
X160430Y-128000D01*
X160873Y-127583D01*
X161317Y-127500D01*
X161760Y-127667D01*
X162077Y-128083D01*
G01X166100Y-132500D02*
Y-127500D01*
X165340Y-128500D01*
G01Y-132500D02*
X166860D01*
G01X171960D02*
Y-127500D01*
X169617Y-131083D01*
X172783D01*
G01X191000Y-62500D02*
Y-137500D01*
G01Y-112500D02*
X294000D01*
Y-87500D01*
G01X191000D02*
X294000D01*
G01X301507Y-122500D02*
Y-117500D01*
X302773D01*
X303280Y-117750D01*
X303660Y-118083D01*
X303977Y-118583D01*
X304230Y-119167D01*
X304293Y-120000D01*
X304230Y-120833D01*
X303977Y-121417D01*
X303660Y-121917D01*
X303280Y-122250D01*
X302773Y-122500D01*
X301507D01*
G01X306417D02*
X308000Y-117500D01*
X309583Y-122500D01*
G01X309013Y-120750D02*
X306987D01*
G01X313100Y-117500D02*
Y-122500D01*
G01X311643Y-117500D02*
X314557D01*
G01X319467Y-122500D02*
X316933D01*
Y-117500D01*
X319467D01*
G01X318453Y-119917D02*
X316933D01*
G01X323300Y-122667D02*
X323173Y-122583D01*
Y-122417D01*
X323300Y-122333D01*
X323427Y-122417D01*
Y-122583D01*
X323300Y-122667D01*
G01Y-120417D02*
X323173Y-120333D01*
Y-120167D01*
X323300Y-120083D01*
X323427Y-120167D01*
Y-120333D01*
X323300Y-120417D01*
G01X296000Y-62500D02*
Y-137500D01*
G01X294000Y-62500D02*
Y-137500D01*
G01X301633Y-97500D02*
Y-92500D01*
X303153D01*
X303660Y-92750D01*
X304040Y-93333D01*
X304167Y-94000D01*
X304040Y-94667D01*
X303723Y-95167D01*
X303153Y-95417D01*
X301633D01*
G01X306860Y-97667D02*
X309140Y-92500D01*
G01X311643Y-97500D02*
Y-92500D01*
X314557Y-97500D01*
Y-92500D01*
G01X318200Y-97667D02*
X318073Y-97583D01*
Y-97417D01*
X318200Y-97333D01*
X318327Y-97417D01*
Y-97583D01*
X318200Y-97667D01*
G01Y-95417D02*
X318073Y-95333D01*
Y-95167D01*
X318200Y-95083D01*
X318327Y-95167D01*
Y-95333D01*
X318200Y-95417D01*
G01X296000Y-112500D02*
X496000D01*
G01X301633Y-72500D02*
Y-67500D01*
X303153D01*
X303660Y-67750D01*
X304040Y-68333D01*
X304167Y-69000D01*
X304040Y-69667D01*
X303723Y-70167D01*
X303153Y-70417D01*
X301633D01*
G01X306733Y-72500D02*
Y-67500D01*
X308317D01*
X308823Y-67750D01*
X309140Y-68083D01*
X309267Y-68750D01*
X309140Y-69417D01*
X308760Y-69833D01*
X308317Y-70083D01*
X306733D01*
G01X308317D02*
X309267Y-72500D01*
G01X313100D02*
X312593Y-72417D01*
X312150Y-72083D01*
X311770Y-71583D01*
X311517Y-71000D01*
X311390Y-70333D01*
Y-69667D01*
X311517Y-69000D01*
X311770Y-68417D01*
X312150Y-67917D01*
X312593Y-67583D01*
X313100Y-67500D01*
X313607Y-67583D01*
X314050Y-67917D01*
X314430Y-68417D01*
X314683Y-69000D01*
X314810Y-69667D01*
Y-70333D01*
X314683Y-71000D01*
X314430Y-71583D01*
X314050Y-72083D01*
X313607Y-72417D01*
X313100Y-72500D01*
G01X316933Y-71500D02*
X317250Y-72000D01*
X317630Y-72333D01*
X318073Y-72500D01*
X318580Y-72333D01*
X318960Y-72000D01*
X319340Y-71500D01*
X319467Y-70833D01*
Y-67500D01*
G01X324567Y-72500D02*
X322033D01*
Y-67500D01*
X324567D01*
G01X323553Y-69917D02*
X322033D01*
G01X329793Y-67917D02*
X329413Y-67667D01*
X328970Y-67500D01*
X328463D01*
X327893Y-67750D01*
X327450Y-68167D01*
X327133Y-68667D01*
X326880Y-69500D01*
X326817Y-70250D01*
X326943Y-71000D01*
X327133Y-71500D01*
X327513Y-72000D01*
X327957Y-72333D01*
X328400Y-72500D01*
X328843D01*
X329287Y-72333D01*
X329667Y-72083D01*
X329983Y-71750D01*
G01X333500Y-67500D02*
Y-72500D01*
G01X332043Y-67500D02*
X334957D01*
G01X338600Y-72667D02*
X338473Y-72583D01*
Y-72417D01*
X338600Y-72333D01*
X338727Y-72417D01*
Y-72583D01*
X338600Y-72667D01*
G01Y-70417D02*
X338473Y-70333D01*
Y-70167D01*
X338600Y-70083D01*
X338727Y-70167D01*
Y-70333D01*
X338600Y-70417D01*
G01X296000Y-87500D02*
X496000D01*
G01X411000Y-112500D02*
Y-137500D01*
G01X416633Y-122500D02*
Y-117500D01*
X418217D01*
X418723Y-117750D01*
X419040Y-118083D01*
X419167Y-118750D01*
X419040Y-119417D01*
X418660Y-119833D01*
X418217Y-120083D01*
X416633D01*
G01X418217D02*
X419167Y-122500D01*
G01X424267D02*
X421733D01*
Y-117500D01*
X424267D01*
G01X423253Y-119917D02*
X421733D01*
G01X426517Y-117500D02*
X428100Y-122500D01*
X429683Y-117500D01*
G01X433200Y-122667D02*
X433073Y-122583D01*
Y-122417D01*
X433200Y-122333D01*
X433327Y-122417D01*
Y-122583D01*
X433200Y-122667D01*
G01Y-120417D02*
X433073Y-120333D01*
Y-120167D01*
X433200Y-120083D01*
X433327Y-120167D01*
Y-120333D01*
X433200Y-120417D01*
G01X460000Y-112500D02*
Y-137500D01*
G01X-723776Y2987387D02*
Y-376795D01*
Y-489221D01*
X1782976D01*
Y-376795D01*
Y2987387D01*
X-723776D01*
G01X6705Y-124160D02*
X7332Y-124685D01*
X8037Y-125000D01*
X8663D01*
X9290Y-124685D01*
X9760Y-124160D01*
X9995Y-123425D01*
X9838Y-122690D01*
X9447Y-122060D01*
X8742Y-121640D01*
X7802Y-121430D01*
X7253Y-121010D01*
X7018Y-120275D01*
X7175Y-119540D01*
X7567Y-119015D01*
X8115Y-118700D01*
X8663D01*
X9212Y-118910D01*
X9682Y-119435D01*
G01X13005Y-125000D02*
Y-118700D01*
G01X16295D02*
Y-125000D01*
G01Y-121850D02*
X13005D01*
G01X20010Y-118700D02*
X21890D01*
G01X20950D02*
Y-125000D01*
G01X20010D02*
X21890D01*
G01X28817D02*
X25683D01*
Y-118700D01*
X28817D01*
G01X27563Y-121745D02*
X25683D01*
G01X31748Y-125000D02*
Y-118700D01*
X35352Y-125000D01*
Y-118700D01*
G01X39693Y-126155D02*
X40007Y-124790D01*
G01X46150Y-118700D02*
Y-125000D01*
G01X44348Y-118700D02*
X47952D01*
G01X50492Y-125000D02*
X52450Y-118700D01*
X54408Y-125000D01*
G01X53703Y-122795D02*
X51197D01*
G01X57810Y-118700D02*
X59690D01*
G01X58750D02*
Y-125000D01*
G01X57810D02*
X59690D01*
G01X62700Y-118700D02*
X63797Y-125000D01*
X65050Y-118700D01*
X66303Y-125000D01*
X67400Y-118700D01*
G01X69392Y-125000D02*
X71350Y-118700D01*
X73308Y-125000D01*
G01X72603Y-122795D02*
X70097D01*
G01X75848Y-125000D02*
Y-118700D01*
X79452Y-125000D01*
Y-118700D01*
G01X88683Y-125000D02*
Y-118700D01*
X90642D01*
X91268Y-119015D01*
X91660Y-119435D01*
X91817Y-120275D01*
X91660Y-121115D01*
X91190Y-121640D01*
X90642Y-121955D01*
X88683D01*
G01X90642D02*
X91817Y-125000D01*
G01X96550Y-125210D02*
X96393Y-125105D01*
Y-124895D01*
X96550Y-124790D01*
X96707Y-124895D01*
Y-125105D01*
X96550Y-125210D01*
G01X102850Y-125000D02*
X102223Y-124895D01*
X101675Y-124475D01*
X101205Y-123845D01*
X100892Y-123110D01*
X100735Y-122270D01*
Y-121430D01*
X100892Y-120590D01*
X101205Y-119855D01*
X101675Y-119225D01*
X102223Y-118805D01*
X102850Y-118700D01*
X103477Y-118805D01*
X104025Y-119225D01*
X104495Y-119855D01*
X104808Y-120590D01*
X104965Y-121430D01*
Y-122270D01*
X104808Y-123110D01*
X104495Y-123845D01*
X104025Y-124475D01*
X103477Y-124895D01*
X102850Y-125000D01*
G01X109150Y-125210D02*
X108993Y-125105D01*
Y-124895D01*
X109150Y-124790D01*
X109307Y-124895D01*
Y-125105D01*
X109150Y-125210D01*
G01X117173Y-119225D02*
X116703Y-118910D01*
X116155Y-118700D01*
X115528D01*
X114823Y-119015D01*
X114275Y-119540D01*
X113883Y-120170D01*
X113570Y-121220D01*
X113492Y-122165D01*
X113648Y-123110D01*
X113883Y-123740D01*
X114353Y-124370D01*
X114902Y-124790D01*
X115450Y-125000D01*
X115998D01*
X116547Y-124790D01*
X117017Y-124475D01*
X117408Y-124055D01*
G01X121750Y-125210D02*
X121593Y-125105D01*
Y-124895D01*
X121750Y-124790D01*
X121907Y-124895D01*
Y-125105D01*
X121750Y-125210D01*
G01X6627Y-115000D02*
Y-108700D01*
G01X9603D02*
X6627Y-112585D01*
G01X10073Y-115000D02*
X7958Y-110800D01*
G01X12927Y-108700D02*
Y-113215D01*
X13240Y-114160D01*
X13867Y-114790D01*
X14650Y-115000D01*
X15433Y-114790D01*
X16060Y-114160D01*
X16373Y-113215D01*
Y-108700D01*
G01X22517Y-115000D02*
X19383D01*
Y-108700D01*
X22517D01*
G01X21263Y-111745D02*
X19383D01*
G01X26310Y-108700D02*
X28190D01*
G01X27250D02*
Y-115000D01*
G01X26310D02*
X28190D01*
G01X38205Y-114160D02*
X38832Y-114685D01*
X39537Y-115000D01*
X40163D01*
X40790Y-114685D01*
X41260Y-114160D01*
X41495Y-113425D01*
X41338Y-112690D01*
X40947Y-112060D01*
X40242Y-111640D01*
X39302Y-111430D01*
X38753Y-111010D01*
X38518Y-110275D01*
X38675Y-109540D01*
X39067Y-109015D01*
X39615Y-108700D01*
X40163D01*
X40712Y-108910D01*
X41182Y-109435D01*
G01X44505Y-115000D02*
Y-108700D01*
G01X47795D02*
Y-115000D01*
G01Y-111850D02*
X44505D01*
G01X50492Y-115000D02*
X52450Y-108700D01*
X54408Y-115000D01*
G01X53703Y-112795D02*
X51197D01*
G01X56948Y-115000D02*
Y-108700D01*
X60552Y-115000D01*
Y-108700D01*
G01X69705Y-115000D02*
Y-108700D01*
G01X72995D02*
Y-115000D01*
G01Y-111850D02*
X69705D01*
G01X76005Y-114160D02*
X76632Y-114685D01*
X77337Y-115000D01*
X77963D01*
X78590Y-114685D01*
X79060Y-114160D01*
X79295Y-113425D01*
X79138Y-112690D01*
X78747Y-112060D01*
X78042Y-111640D01*
X77102Y-111430D01*
X76553Y-111010D01*
X76318Y-110275D01*
X76475Y-109540D01*
X76867Y-109015D01*
X77415Y-108700D01*
X77963D01*
X78512Y-108910D01*
X78982Y-109435D01*
G01X83010Y-108700D02*
X84890D01*
G01X83950D02*
Y-115000D01*
G01X83010D02*
X84890D01*
G01X88292D02*
X90250Y-108700D01*
X92208Y-115000D01*
G01X91503Y-112795D02*
X88997D01*
G01X94748Y-115000D02*
Y-108700D01*
X98352Y-115000D01*
Y-108700D01*
G01X103320Y-111850D02*
X104887D01*
Y-113740D01*
X104417Y-114370D01*
X103868Y-114790D01*
X103085Y-115000D01*
X102302Y-114790D01*
X101753Y-114370D01*
X101283Y-113740D01*
X100970Y-113005D01*
X100813Y-112165D01*
Y-111430D01*
X100970Y-110800D01*
X101283Y-110065D01*
X101753Y-109435D01*
X102223Y-109015D01*
X102850Y-108700D01*
X103398D01*
X104025Y-108910D01*
X104495Y-109330D01*
G01X108993Y-116155D02*
X109307Y-114790D01*
G01X115450Y-108700D02*
Y-115000D01*
G01X113648Y-108700D02*
X117252D01*
G01X119792Y-115000D02*
X121750Y-108700D01*
X123708Y-115000D01*
G01X123003Y-112795D02*
X120497D01*
G01X128050Y-115000D02*
X127423Y-114895D01*
X126875Y-114475D01*
X126405Y-113845D01*
X126092Y-113110D01*
X125935Y-112270D01*
Y-111430D01*
X126092Y-110590D01*
X126405Y-109855D01*
X126875Y-109225D01*
X127423Y-108805D01*
X128050Y-108700D01*
X128677Y-108805D01*
X129225Y-109225D01*
X129695Y-109855D01*
X130008Y-110590D01*
X130165Y-111430D01*
Y-112270D01*
X130008Y-113110D01*
X129695Y-113845D01*
X129225Y-114475D01*
X128677Y-114895D01*
X128050Y-115000D01*
G01X140650D02*
Y-112165D01*
X139083Y-108700D01*
G01X142217D02*
X140650Y-112165D01*
G01X145227Y-108700D02*
Y-113215D01*
X145540Y-114160D01*
X146167Y-114790D01*
X146950Y-115000D01*
X147733Y-114790D01*
X148360Y-114160D01*
X148673Y-113215D01*
Y-108700D01*
G01X151292Y-115000D02*
X153250Y-108700D01*
X155208Y-115000D01*
G01X154503Y-112795D02*
X151997D01*
G01X157748Y-115000D02*
Y-108700D01*
X161352Y-115000D01*
Y-108700D01*
G01X30650Y-92300D02*
X28130Y-91883D01*
X25925Y-90217D01*
X24035Y-87717D01*
X22775Y-84800D01*
X22145Y-81467D01*
Y-78133D01*
X22775Y-74800D01*
X24035Y-71883D01*
X25925Y-69384D01*
X28130Y-67717D01*
X30650Y-67300D01*
X33170Y-67717D01*
X35375Y-69384D01*
X37265Y-71883D01*
X38525Y-74800D01*
X39155Y-78133D01*
Y-81467D01*
X38525Y-84800D01*
X37265Y-87717D01*
X35375Y-90217D01*
X33170Y-91883D01*
X30650Y-92300D01*
G01X33170Y-85633D02*
X36950Y-92300D01*
G01X50495Y-75634D02*
Y-87300D01*
X51755Y-90217D01*
X53645Y-91883D01*
X55850Y-92300D01*
X58055Y-91883D01*
X59945Y-90217D01*
X61205Y-87300D01*
G01Y-92300D02*
Y-75634D01*
G01X86720Y-92300D02*
Y-75634D01*
G01Y-78550D02*
X85460Y-76884D01*
X83570Y-76050D01*
X81365Y-75634D01*
X79160Y-76467D01*
X77270Y-78133D01*
X76010Y-80634D01*
X75380Y-83967D01*
X76010Y-87300D01*
X77270Y-89801D01*
X79160Y-91467D01*
X81365Y-92300D01*
X83570Y-91883D01*
X85460Y-90634D01*
X86720Y-88967D01*
G01X100895Y-92300D02*
Y-75634D01*
G01Y-79800D02*
X102155Y-77717D01*
X104045Y-76050D01*
X106565Y-75634D01*
X108770Y-76050D01*
X110660Y-77717D01*
X111605Y-80634D01*
Y-92300D01*
G01X131450Y-67300D02*
Y-92300D01*
G01X127040Y-75634D02*
X135860D01*
G01X162320Y-92300D02*
Y-75634D01*
G01Y-78550D02*
X161060Y-76884D01*
X159170Y-76050D01*
X156965Y-75634D01*
X154760Y-76467D01*
X152870Y-78133D01*
X151610Y-80634D01*
X150980Y-83967D01*
X151610Y-87300D01*
X152870Y-89801D01*
X154760Y-91467D01*
X156965Y-92300D01*
X159170Y-91883D01*
X161060Y-90634D01*
X162320Y-88967D01*
G01X6548Y-105000D02*
Y-98700D01*
X10152Y-105000D01*
Y-98700D01*
G01X14650Y-105000D02*
X14023Y-104895D01*
X13475Y-104475D01*
X13005Y-103845D01*
X12692Y-103110D01*
X12535Y-102270D01*
Y-101430D01*
X12692Y-100590D01*
X13005Y-99855D01*
X13475Y-99225D01*
X14023Y-98805D01*
X14650Y-98700D01*
X15277Y-98805D01*
X15825Y-99225D01*
X16295Y-99855D01*
X16608Y-100590D01*
X16765Y-101430D01*
Y-102270D01*
X16608Y-103110D01*
X16295Y-103845D01*
X15825Y-104475D01*
X15277Y-104895D01*
X14650Y-105000D01*
G01X20950Y-105210D02*
X20793Y-105105D01*
Y-104895D01*
X20950Y-104790D01*
X21107Y-104895D01*
Y-105105D01*
X20950Y-105210D01*
G01X27250Y-105000D02*
Y-98700D01*
X26310Y-99960D01*
G01Y-105000D02*
X28190D01*
G01X33550D02*
X34098Y-104895D01*
X34725Y-104580D01*
X35117Y-104055D01*
X35273Y-103320D01*
X35117Y-102585D01*
X34647Y-101955D01*
X33942Y-101640D01*
X33158D01*
X32688Y-101430D01*
X32297Y-100905D01*
X32140Y-100170D01*
X32375Y-99435D01*
X32923Y-98910D01*
X33550Y-98700D01*
X34177Y-98910D01*
X34725Y-99435D01*
X34960Y-100170D01*
X34803Y-100905D01*
X34412Y-101430D01*
X33942Y-101640D01*
X33158D01*
X32453Y-101955D01*
X31983Y-102585D01*
X31827Y-103320D01*
X31983Y-104055D01*
X32375Y-104580D01*
X33002Y-104895D01*
X33550Y-105000D01*
G01X39850D02*
X40398Y-104895D01*
X41025Y-104580D01*
X41417Y-104055D01*
X41573Y-103320D01*
X41417Y-102585D01*
X40947Y-101955D01*
X40242Y-101640D01*
X39458D01*
X38988Y-101430D01*
X38597Y-100905D01*
X38440Y-100170D01*
X38675Y-99435D01*
X39223Y-98910D01*
X39850Y-98700D01*
X40477Y-98910D01*
X41025Y-99435D01*
X41260Y-100170D01*
X41103Y-100905D01*
X40712Y-101430D01*
X40242Y-101640D01*
X39458D01*
X38753Y-101955D01*
X38283Y-102585D01*
X38127Y-103320D01*
X38283Y-104055D01*
X38675Y-104580D01*
X39302Y-104895D01*
X39850Y-105000D01*
G01X45993Y-106155D02*
X46307Y-104790D01*
G01X50100Y-98700D02*
X51197Y-105000D01*
X52450Y-98700D01*
X53703Y-105000D01*
X54800Y-98700D01*
G01X60317Y-105000D02*
X57183D01*
Y-98700D01*
X60317D01*
G01X59063Y-101745D02*
X57183D01*
G01X63248Y-105000D02*
Y-98700D01*
X66852Y-105000D01*
Y-98700D01*
G01X76005Y-105000D02*
Y-98700D01*
G01X79295D02*
Y-105000D01*
G01Y-101850D02*
X76005D01*
G01X81600Y-98700D02*
X82697Y-105000D01*
X83950Y-98700D01*
X85203Y-105000D01*
X86300Y-98700D01*
G01X88292Y-105000D02*
X90250Y-98700D01*
X92208Y-105000D01*
G01X91503Y-102795D02*
X88997D01*
G01X101362Y-99750D02*
X101832Y-99120D01*
X102380Y-98805D01*
X103007Y-98700D01*
X103790Y-98910D01*
X104338Y-99435D01*
X104495Y-100065D01*
X104417Y-100695D01*
X104103Y-101220D01*
X102537Y-102270D01*
X101832Y-103005D01*
X101362Y-104055D01*
X101205Y-105000D01*
X104495D01*
G01X107348D02*
Y-98700D01*
X110952Y-105000D01*
Y-98700D01*
G01X113727Y-105000D02*
Y-98700D01*
X115293D01*
X115920Y-99015D01*
X116390Y-99435D01*
X116782Y-100065D01*
X117095Y-100800D01*
X117173Y-101850D01*
X117095Y-102900D01*
X116782Y-103635D01*
X116390Y-104265D01*
X115920Y-104685D01*
X115293Y-105000D01*
X113727D01*
G01X126483D02*
Y-98700D01*
X128442D01*
X129068Y-99015D01*
X129460Y-99435D01*
X129617Y-100275D01*
X129460Y-101115D01*
X128990Y-101640D01*
X128442Y-101955D01*
X126483D01*
G01X128442D02*
X129617Y-105000D01*
G01X132627D02*
Y-98700D01*
X134193D01*
X134820Y-99015D01*
X135290Y-99435D01*
X135682Y-100065D01*
X135995Y-100800D01*
X136073Y-101850D01*
X135995Y-102900D01*
X135682Y-103635D01*
X135290Y-104265D01*
X134820Y-104685D01*
X134193Y-105000D01*
X132627D01*
G01X140650Y-105210D02*
X140493Y-105105D01*
Y-104895D01*
X140650Y-104790D01*
X140807Y-104895D01*
Y-105105D01*
X140650Y-105210D01*
G01X215400Y-105000D02*
Y-97000D01*
X218000Y-103667D01*
X220600Y-97000D01*
Y-105000D01*
G01X223500D02*
X226000Y-97000D01*
X228500Y-105000D01*
G01X227600Y-102200D02*
X224400D01*
G01X231900Y-103934D02*
X232700Y-104600D01*
X233600Y-105000D01*
X234400D01*
X235200Y-104600D01*
X235800Y-103934D01*
X236100Y-103000D01*
X235900Y-102067D01*
X235400Y-101267D01*
X234500Y-100733D01*
X233300Y-100467D01*
X232600Y-99933D01*
X232300Y-99000D01*
X232500Y-98067D01*
X233000Y-97400D01*
X233700Y-97000D01*
X234400D01*
X235100Y-97267D01*
X235700Y-97933D01*
G01X239800Y-105000D02*
Y-97000D01*
G01X243600D02*
X239800Y-101934D01*
G01X244200Y-105000D02*
X241500Y-99667D01*
G01X248700Y-102333D02*
X251300D01*
G01X258000Y-97000D02*
Y-105000D01*
G01X255700Y-97000D02*
X260300D01*
G01X266000Y-105000D02*
X265200Y-104867D01*
X264500Y-104333D01*
X263900Y-103533D01*
X263500Y-102600D01*
X263300Y-101533D01*
Y-100467D01*
X263500Y-99400D01*
X263900Y-98467D01*
X264500Y-97667D01*
X265200Y-97133D01*
X266000Y-97000D01*
X266800Y-97133D01*
X267500Y-97667D01*
X268100Y-98467D01*
X268500Y-99400D01*
X268700Y-100467D01*
Y-101533D01*
X268500Y-102600D01*
X268100Y-103533D01*
X267500Y-104333D01*
X266800Y-104867D01*
X266000Y-105000D01*
G01X272000D02*
Y-97000D01*
X274400D01*
X275200Y-97400D01*
X275800Y-98333D01*
X276000Y-99400D01*
X275800Y-100467D01*
X275300Y-101267D01*
X274400Y-101667D01*
X272000D01*
G01X202000Y-72000D02*
Y-80000D01*
X206000D01*
G01X213800D02*
Y-74667D01*
G01Y-75600D02*
X213400Y-75067D01*
X212800Y-74800D01*
X212100Y-74667D01*
X211400Y-74933D01*
X210800Y-75467D01*
X210400Y-76267D01*
X210200Y-77333D01*
X210400Y-78400D01*
X210800Y-79200D01*
X211400Y-79733D01*
X212100Y-80000D01*
X212800Y-79867D01*
X213400Y-79467D01*
X213800Y-78934D01*
G01X217900Y-82400D02*
X218500Y-82667D01*
X219300Y-82400D01*
X219800Y-81867D01*
X220200Y-81200D01*
X220800Y-79067D01*
X222100Y-74667D01*
G01X218900D02*
X220800Y-79067D01*
G01X226500Y-76400D02*
X229700D01*
X229400Y-75467D01*
X228900Y-74933D01*
X228200Y-74667D01*
X227500Y-74800D01*
X226900Y-75200D01*
X226500Y-76133D01*
X226300Y-76934D01*
Y-77733D01*
X226500Y-78533D01*
X227000Y-79333D01*
X227600Y-79867D01*
X228300Y-80000D01*
X229000Y-79733D01*
X229700Y-78934D01*
G01X234600Y-80000D02*
Y-74667D01*
G01Y-75733D02*
X235100Y-75200D01*
X235600Y-74800D01*
X236300Y-74667D01*
X236800Y-74800D01*
X237400Y-75200D01*
G01X225500Y-122000D02*
Y-130000D01*
G01X223200Y-122000D02*
X227800D01*
G01X233500Y-124667D02*
Y-130000D01*
G01Y-122533D02*
X233300Y-122400D01*
Y-122133D01*
X233500Y-122000D01*
X233700Y-122133D01*
Y-122400D01*
X233500Y-122533D01*
G01X239800Y-130000D02*
Y-124667D01*
G01Y-126000D02*
X240200Y-125333D01*
X240800Y-124800D01*
X241600Y-124667D01*
X242300Y-124800D01*
X242900Y-125333D01*
X243200Y-126267D01*
Y-130000D01*
G01X251300D02*
Y-124667D01*
G01Y-125600D02*
X250900Y-125067D01*
X250300Y-124800D01*
X249600Y-124667D01*
X248900Y-124933D01*
X248300Y-125467D01*
X247900Y-126267D01*
X247700Y-127333D01*
X247900Y-128400D01*
X248300Y-129200D01*
X248900Y-129733D01*
X249600Y-130000D01*
X250300Y-129867D01*
X250900Y-129467D01*
X251300Y-128934D01*
G01X328600Y-123333D02*
X329200Y-122533D01*
X329900Y-122133D01*
X330700Y-122000D01*
X331700Y-122267D01*
X332400Y-122933D01*
X332600Y-123733D01*
X332500Y-124534D01*
X332100Y-125200D01*
X330100Y-126533D01*
X329200Y-127467D01*
X328600Y-128800D01*
X328400Y-130000D01*
X332600D01*
G01X338500Y-122000D02*
X337700Y-122267D01*
X337100Y-122933D01*
X336700Y-123733D01*
X336400Y-124800D01*
X336300Y-126000D01*
X336400Y-127200D01*
X336700Y-128267D01*
X337100Y-129067D01*
X337700Y-129733D01*
X338500Y-130000D01*
X339300Y-129733D01*
X339900Y-129067D01*
X340300Y-128267D01*
X340600Y-127200D01*
X340700Y-126000D01*
X340600Y-124800D01*
X340300Y-123733D01*
X339900Y-122933D01*
X339300Y-122267D01*
X338500Y-122000D01*
G01X346500Y-130000D02*
Y-122000D01*
X345300Y-123600D01*
G01Y-130000D02*
X347700D01*
G01X352300Y-128400D02*
X352900Y-129333D01*
X353700Y-129867D01*
X354600Y-130000D01*
X355400Y-129867D01*
X356200Y-129200D01*
X356700Y-128400D01*
X356800Y-127600D01*
X356600Y-126667D01*
X355900Y-126000D01*
X355200Y-125733D01*
X354300D01*
G01X355200D02*
X355800Y-125333D01*
X356300Y-124667D01*
X356500Y-123867D01*
X356300Y-123067D01*
X355800Y-122400D01*
X354900Y-122000D01*
X354000Y-122133D01*
X353100Y-122667D01*
G01X360700Y-130267D02*
X364300Y-122000D01*
G01X370500D02*
X369700Y-122267D01*
X369100Y-122933D01*
X368700Y-123733D01*
X368400Y-124800D01*
X368300Y-126000D01*
X368400Y-127200D01*
X368700Y-128267D01*
X369100Y-129067D01*
X369700Y-129733D01*
X370500Y-130000D01*
X371300Y-129733D01*
X371900Y-129067D01*
X372300Y-128267D01*
X372600Y-127200D01*
X372700Y-126000D01*
X372600Y-124800D01*
X372300Y-123733D01*
X371900Y-122933D01*
X371300Y-122267D01*
X370500Y-122000D01*
G01X378500Y-130000D02*
Y-122000D01*
X377300Y-123600D01*
G01Y-130000D02*
X379700D01*
G01X384700Y-130267D02*
X388300Y-122000D01*
G01X394500D02*
X393700Y-122267D01*
X393100Y-122933D01*
X392700Y-123733D01*
X392400Y-124800D01*
X392300Y-126000D01*
X392400Y-127200D01*
X392700Y-128267D01*
X393100Y-129067D01*
X393700Y-129733D01*
X394500Y-130000D01*
X395300Y-129733D01*
X395900Y-129067D01*
X396300Y-128267D01*
X396600Y-127200D01*
X396700Y-126000D01*
X396600Y-124800D01*
X396300Y-123733D01*
X395900Y-122933D01*
X395300Y-122267D01*
X394500Y-122000D01*
G01X400800Y-129067D02*
X401500Y-129733D01*
X402300Y-130000D01*
X403100Y-129733D01*
X403800Y-128934D01*
X404300Y-127733D01*
X404500Y-126533D01*
Y-125067D01*
X404300Y-123867D01*
X403800Y-122800D01*
X403200Y-122267D01*
X402500Y-122000D01*
X401700Y-122267D01*
X401100Y-122800D01*
X400700Y-123600D01*
X400500Y-124667D01*
X400700Y-125600D01*
X401200Y-126533D01*
X401800Y-127067D01*
X402500Y-127200D01*
X403300Y-126934D01*
X403900Y-126267D01*
X404500Y-125067D01*
G01X328300Y-105000D02*
Y-97000D01*
X330300D01*
X331100Y-97400D01*
X331700Y-97933D01*
X332200Y-98733D01*
X332600Y-99667D01*
X332700Y-101000D01*
X332600Y-102333D01*
X332200Y-103267D01*
X331700Y-104067D01*
X331100Y-104600D01*
X330300Y-105000D01*
X328300D01*
G01X336000D02*
X338500Y-97000D01*
X341000Y-105000D01*
G01X340100Y-102200D02*
X336900D01*
G01X346500Y-97000D02*
Y-105000D01*
G01X344200Y-97000D02*
X348800D01*
G01X352600Y-101667D02*
X353300Y-100733D01*
X353900Y-100200D01*
X354700Y-99933D01*
X355400Y-100200D01*
X355900Y-100733D01*
X356300Y-101533D01*
X356400Y-102467D01*
X356300Y-103267D01*
X355900Y-104067D01*
X355300Y-104733D01*
X354600Y-105000D01*
X353800Y-104733D01*
X353100Y-103934D01*
X352700Y-102733D01*
X352600Y-101400D01*
X352800Y-99667D01*
X353100Y-98733D01*
X353600Y-97800D01*
X354300Y-97133D01*
X355000Y-97000D01*
X355700Y-97267D01*
X356200Y-97933D01*
G01X359900Y-105000D02*
Y-97000D01*
X362500Y-103667D01*
X365100Y-97000D01*
Y-105000D01*
G01X370500Y-97000D02*
Y-105000D01*
G01X368200Y-97000D02*
X372800D01*
G01X379300Y-100733D02*
X379700Y-100333D01*
X380000Y-99667D01*
X380200Y-98733D01*
X380000Y-97933D01*
X379600Y-97400D01*
X378900Y-97000D01*
X376200D01*
Y-105000D01*
X379500D01*
X380200Y-104467D01*
X380600Y-103667D01*
X380800Y-102733D01*
X380600Y-101800D01*
X380000Y-101000D01*
X379300Y-100733D01*
X376200D01*
G01X386500Y-105000D02*
X387200Y-104867D01*
X388000Y-104467D01*
X388500Y-103800D01*
X388700Y-102867D01*
X388500Y-101934D01*
X387900Y-101133D01*
X387000Y-100733D01*
X386000D01*
X385400Y-100467D01*
X384900Y-99800D01*
X384700Y-98867D01*
X385000Y-97933D01*
X385700Y-97267D01*
X386500Y-97000D01*
X387300Y-97267D01*
X388000Y-97933D01*
X388300Y-98867D01*
X388100Y-99800D01*
X387600Y-100467D01*
X387000Y-100733D01*
X386000D01*
X385100Y-101133D01*
X384500Y-101934D01*
X384300Y-102867D01*
X384500Y-103800D01*
X385000Y-104467D01*
X385800Y-104867D01*
X386500Y-105000D01*
G01X394500D02*
X395200Y-104867D01*
X396000Y-104467D01*
X396500Y-103800D01*
X396700Y-102867D01*
X396500Y-101934D01*
X395900Y-101133D01*
X395000Y-100733D01*
X394000D01*
X393400Y-100467D01*
X392900Y-99800D01*
X392700Y-98867D01*
X393000Y-97933D01*
X393700Y-97267D01*
X394500Y-97000D01*
X395300Y-97267D01*
X396000Y-97933D01*
X396300Y-98867D01*
X396100Y-99800D01*
X395600Y-100467D01*
X395000Y-100733D01*
X394000D01*
X393100Y-101133D01*
X392500Y-101934D01*
X392300Y-102867D01*
X392500Y-103800D01*
X393000Y-104467D01*
X393800Y-104867D01*
X394500Y-105000D01*
G01X400000D02*
X402500Y-97000D01*
X405000Y-105000D01*
G01X404100Y-102200D02*
X400900D01*
G01X410500Y-97000D02*
X409700Y-97267D01*
X409100Y-97933D01*
X408700Y-98733D01*
X408400Y-99800D01*
X408300Y-101000D01*
X408400Y-102200D01*
X408700Y-103267D01*
X409100Y-104067D01*
X409700Y-104733D01*
X410500Y-105000D01*
X411300Y-104733D01*
X411900Y-104067D01*
X412300Y-103267D01*
X412600Y-102200D01*
X412700Y-101000D01*
X412600Y-99800D01*
X412300Y-98733D01*
X411900Y-97933D01*
X411300Y-97267D01*
X410500Y-97000D01*
G01X350500Y-72000D02*
Y-80000D01*
G01X348200Y-72000D02*
X352800D01*
G01X356600Y-76667D02*
X357300Y-75733D01*
X357900Y-75200D01*
X358700Y-74933D01*
X359400Y-75200D01*
X359900Y-75733D01*
X360300Y-76533D01*
X360400Y-77467D01*
X360300Y-78267D01*
X359900Y-79067D01*
X359300Y-79733D01*
X358600Y-80000D01*
X357800Y-79733D01*
X357100Y-78934D01*
X356700Y-77733D01*
X356600Y-76400D01*
X356800Y-74667D01*
X357100Y-73733D01*
X357600Y-72800D01*
X358300Y-72133D01*
X359000Y-72000D01*
X359700Y-72267D01*
X360200Y-72933D01*
G01X363900Y-80000D02*
Y-72000D01*
X366500Y-78667D01*
X369100Y-72000D01*
Y-80000D01*
G01X375100Y-76000D02*
X377100D01*
Y-78400D01*
X376500Y-79200D01*
X375800Y-79733D01*
X374800Y-80000D01*
X373800Y-79733D01*
X373100Y-79200D01*
X372500Y-78400D01*
X372100Y-77467D01*
X371900Y-76400D01*
Y-75467D01*
X372100Y-74667D01*
X372500Y-73733D01*
X373100Y-72933D01*
X373700Y-72400D01*
X374500Y-72000D01*
X375200D01*
X376000Y-72267D01*
X376600Y-72800D01*
G01X379500Y-82667D02*
X385500D01*
G01X388500Y-80000D02*
Y-72000D01*
X390900D01*
X391700Y-72400D01*
X392300Y-73333D01*
X392500Y-74400D01*
X392300Y-75467D01*
X391800Y-76267D01*
X390900Y-76667D01*
X388500D01*
G01X396300Y-80000D02*
Y-72000D01*
X398300D01*
X399100Y-72400D01*
X399700Y-72933D01*
X400200Y-73733D01*
X400600Y-74667D01*
X400700Y-76000D01*
X400600Y-77333D01*
X400200Y-78267D01*
X399700Y-79067D01*
X399100Y-79600D01*
X398300Y-80000D01*
X396300D01*
G01X407300Y-75733D02*
X407700Y-75333D01*
X408000Y-74667D01*
X408200Y-73733D01*
X408000Y-72933D01*
X407600Y-72400D01*
X406900Y-72000D01*
X404200D01*
Y-80000D01*
X407500D01*
X408200Y-79467D01*
X408600Y-78667D01*
X408800Y-77733D01*
X408600Y-76800D01*
X408000Y-76000D01*
X407300Y-75733D01*
X404200D01*
G01X411500Y-82667D02*
X417500D01*
G01X420000Y-80000D02*
X422500Y-72000D01*
X425000Y-80000D01*
G01X424100Y-77200D02*
X420900D01*
G01X427500Y-82667D02*
X433500D01*
G01X439300Y-75733D02*
X439700Y-75333D01*
X440000Y-74667D01*
X440200Y-73733D01*
X440000Y-72933D01*
X439600Y-72400D01*
X438900Y-72000D01*
X436200D01*
Y-80000D01*
X439500D01*
X440200Y-79467D01*
X440600Y-78667D01*
X440800Y-77733D01*
X440600Y-76800D01*
X440000Y-76000D01*
X439300Y-75733D01*
X436200D01*
G01X444300Y-80000D02*
Y-72000D01*
X446300D01*
X447100Y-72400D01*
X447700Y-72933D01*
X448200Y-73733D01*
X448600Y-74667D01*
X448700Y-76000D01*
X448600Y-77333D01*
X448200Y-78267D01*
X447700Y-79067D01*
X447100Y-79600D01*
X446300Y-80000D01*
X444300D01*
G01X443000Y-130000D02*
X445500Y-122000D01*
X448000Y-130000D01*
G01X447100Y-127200D02*
X443900D01*
G01X473000Y-130000D02*
Y-122000D01*
X471800Y-123600D01*
G01Y-130000D02*
X474200D01*
G01X479100Y-126667D02*
X479800Y-125733D01*
X480400Y-125200D01*
X481200Y-124933D01*
X481900Y-125200D01*
X482400Y-125733D01*
X482800Y-126533D01*
X482900Y-127467D01*
X482800Y-128267D01*
X482400Y-129067D01*
X481800Y-129733D01*
X481100Y-130000D01*
X480300Y-129733D01*
X479600Y-128934D01*
X479200Y-127733D01*
X479100Y-126400D01*
X479300Y-124667D01*
X479600Y-123733D01*
X480100Y-122800D01*
X480800Y-122133D01*
X481500Y-122000D01*
X482200Y-122267D01*
X482700Y-122933D01*
G54D27*
X65354Y114960D03*
Y464960D03*
Y814960D03*
Y1164960D03*
Y1514960D03*
Y1864960D03*
X307086Y127165D03*
Y477165D03*
Y827165D03*
Y1343504D03*
Y1693504D03*
X307087Y2043503D03*
G54D36*
X119920Y328071D03*
Y676102D03*
Y1024134D03*
Y1372165D03*
Y1720197D03*
Y2068228D03*
G54D18*
X25389Y1030199D03*
X25393Y1388464D03*
G54D37*
X163385Y27205D03*
Y202205D03*
Y377205D03*
X163386Y552205D03*
Y727205D03*
X163385Y902205D03*
Y1077205D03*
Y1252205D03*
Y1427205D03*
Y1602205D03*
Y1777205D03*
Y1952205D03*
X373385Y32520D03*
Y207520D03*
Y382520D03*
X373386Y557520D03*
Y732520D03*
X373385Y907520D03*
Y1082520D03*
Y1257520D03*
Y1432520D03*
Y1607520D03*
Y1782520D03*
Y1957520D03*
G54D19*
X14691Y1559284D03*
X11541D03*
X54014Y904196D03*
X50864D03*
X54413Y1253378D03*
X51263D03*
X54210Y1263103D03*
X51060D03*
X54277Y1257633D03*
X51127D03*
X54582Y1279783D03*
X51432D03*
X54548Y1267290D03*
X51398D03*
X54446Y1284038D03*
X51296D03*
X54582Y1275630D03*
X51432D03*
X54481Y1271544D03*
X51331D03*
X59609Y1778371D03*
X62759D03*
X62637Y1782985D03*
X59487D03*
X86266Y1771103D03*
X83116D03*
X105845Y20080D03*
X108995D03*
X100778Y28320D03*
X103928D03*
X100693Y24203D03*
X103843D03*
X105845Y15847D03*
X108995D03*
X108090Y46285D03*
X104940D03*
X104932Y41803D03*
X108082D03*
X100778Y32853D03*
X103928D03*
X100778Y37438D03*
X103928D03*
X104137Y78186D03*
X107287D03*
X102727Y58250D03*
X105877D03*
X100518Y391220D03*
X103668D03*
X100518Y376580D03*
X103668D03*
X100518Y386235D03*
X103668D03*
X100518Y381386D03*
X103668D03*
X100518Y371909D03*
X103668D03*
X100518Y396024D03*
X103668D03*
X100794Y400352D03*
X103944D03*
X104518Y426104D03*
X107668D03*
X101056Y720745D03*
X104206D03*
X101056Y730398D03*
X104206D03*
X101056Y725457D03*
X104206D03*
X101056Y715937D03*
X104206D03*
X104346Y745139D03*
X101196D03*
X101056Y735248D03*
X104206D03*
X101056Y739962D03*
X104206D03*
X101520Y749481D03*
X104670D03*
X104442Y774100D03*
X107592D03*
X101189Y1067515D03*
X104339D03*
X101189Y1092036D03*
X104339D03*
X101189Y1072226D03*
X104339D03*
X101189Y1081791D03*
X104339D03*
X101189Y1076901D03*
X104339D03*
X101189Y1087095D03*
X104339D03*
X104432Y1096403D03*
X101282D03*
X105880Y1102535D03*
X109030D03*
X105684Y1122166D03*
X108834D03*
X100227Y1419492D03*
X103377D03*
X100227Y1429195D03*
X103377D03*
X100227Y1424340D03*
X103377D03*
X103443Y1447919D03*
X100293D03*
X100227Y1443743D03*
X103377D03*
X100227Y1434041D03*
X103377D03*
X100227Y1438980D03*
X103377D03*
X100019Y1453131D03*
X103169D03*
X105390Y1470205D03*
X108540D03*
X101677Y1760827D03*
X104827D03*
X101677Y1770527D03*
X104827D03*
X101677Y1765722D03*
X104827D03*
X104930Y1789947D03*
X101780D03*
X101677Y1785571D03*
X104827D03*
X101677Y1775514D03*
X104827D03*
X101677Y1780542D03*
X104827D03*
X105669Y1818228D03*
X108819D03*
X103671Y1798224D03*
X106821D03*
X159676Y56744D03*
X156526D03*
X158463Y68130D03*
X155313D03*
X155202Y72497D03*
X158352D03*
X158559Y88108D03*
X155409D03*
X158490Y407575D03*
X155340D03*
X158498Y436119D03*
X155348D03*
X158950Y756757D03*
X155800D03*
X158665Y764231D03*
X155515D03*
X155113Y776673D03*
X158263D03*
X158519Y784141D03*
X155369D03*
X159278Y1106853D03*
X156128D03*
X158497Y1132178D03*
X155347D03*
X160252Y1457084D03*
X157102D03*
X158976Y1480269D03*
X155826D03*
X159505Y1462651D03*
X156355D03*
X155648Y1473020D03*
X158798D03*
X158840Y1807740D03*
X155690D03*
X158563Y1815631D03*
X155413D03*
X158806Y1828225D03*
X155656D03*
X155409Y1820360D03*
X158559D03*
X184373Y937979D03*
X181223D03*
X184284Y943579D03*
X181134D03*
X184196Y962671D03*
X181046D03*
X184285Y957071D03*
X181135D03*
X184539Y973554D03*
X181389D03*
X184397Y990958D03*
X181247D03*
X184632Y979154D03*
X181482D03*
X184353Y996558D03*
X181203D03*
X184118Y1015313D03*
X180968D03*
X184115Y1009713D03*
X180965D03*
X182329Y1025022D03*
X179179D03*
X182327Y1030622D03*
X179177D03*
X264685Y128228D03*
X261535D03*
X264929Y115559D03*
X261779D03*
X264175Y823604D03*
X261025D03*
X264335Y812170D03*
X261185D03*
X272111Y463099D03*
X268961D03*
X272038Y473677D03*
X268888D03*
X288712Y1864565D03*
X285562D03*
X288794Y1858668D03*
X285644D03*
X308906Y1524401D03*
X305756D03*
X308636Y1513883D03*
X305486D03*
X320208Y1162266D03*
X317058D03*
X320264Y1172804D03*
X317114D03*
G54D28*
X55254Y554500D03*
Y1612504D03*
G54D29*
X72180Y675710D03*
Y680710D03*
Y685710D03*
Y690710D03*
X92980Y680710D03*
Y675710D03*
Y690710D03*
Y685710D03*
G54D38*
X173385Y32520D03*
Y207520D03*
Y382520D03*
X173386Y557520D03*
Y732520D03*
X173385Y907520D03*
Y1082520D03*
Y1257520D03*
Y1432520D03*
Y1607520D03*
Y1782520D03*
Y1957520D03*
G54D39*
Y21890D03*
X183385Y32520D03*
Y21890D03*
X193385Y32520D03*
Y21890D03*
X173385Y196890D03*
X183385D03*
X193385D03*
X183385Y207520D03*
X193385D03*
X173385Y371890D03*
X183385D03*
X193385D03*
X183385Y382520D03*
X193385D03*
X173386Y546890D03*
X183386Y557520D03*
Y546890D03*
X193386Y557520D03*
Y546890D03*
X173386Y721890D03*
X183386Y732520D03*
Y721890D03*
X193386Y732520D03*
Y721890D03*
X173385Y896890D03*
X183385D03*
X193385D03*
X183385Y907520D03*
X193385D03*
X173385Y1071890D03*
X183385D03*
X193385D03*
X183385Y1082520D03*
X193385D03*
X173385Y1246890D03*
X183385Y1257520D03*
Y1246890D03*
X193385Y1257520D03*
Y1246890D03*
X173385Y1421890D03*
X183385Y1432520D03*
Y1421890D03*
X193385Y1432520D03*
Y1421890D03*
X173385Y1596890D03*
X183385D03*
X193385D03*
X183385Y1607520D03*
X193385D03*
X173385Y1771890D03*
X183385D03*
X193385D03*
X183385Y1782520D03*
X193385D03*
X173385Y1946890D03*
X183385Y1957520D03*
Y1946890D03*
X193385Y1957520D03*
Y1946890D03*
X203385Y32520D03*
Y21890D03*
X213385Y32520D03*
Y21890D03*
X203385Y196890D03*
X213385D03*
X203385Y207520D03*
X213385D03*
X203385Y371890D03*
X213385D03*
X203385Y382520D03*
X213385D03*
X203386Y557520D03*
Y546890D03*
X213386Y557520D03*
Y546890D03*
X203386Y732520D03*
Y721890D03*
X213386Y732520D03*
Y721890D03*
X203385Y896890D03*
X213385D03*
X203385Y907520D03*
X213385D03*
X203385Y1071890D03*
X213385D03*
X203385Y1082520D03*
X213385D03*
X203385Y1257520D03*
Y1246890D03*
X213385Y1257520D03*
Y1246890D03*
X203385Y1432520D03*
Y1421890D03*
X213385Y1432520D03*
Y1421890D03*
X203385Y1596890D03*
X213385D03*
X203385Y1607520D03*
X213385D03*
X203385Y1771890D03*
X213385D03*
X203385Y1782520D03*
X213385D03*
X203385Y1957520D03*
Y1946890D03*
X213385Y1957520D03*
Y1946890D03*
X223385Y32520D03*
Y21890D03*
X233385Y32520D03*
Y21890D03*
X243385Y32520D03*
Y21890D03*
X223385Y196890D03*
X233385D03*
X243385D03*
X223385Y207520D03*
X233385D03*
X243385D03*
X223385Y371890D03*
X233385D03*
X243385D03*
X223385Y382520D03*
X233385D03*
X243385D03*
X223386Y557520D03*
Y546890D03*
X233386Y557520D03*
Y546890D03*
X243386Y557520D03*
Y546890D03*
X223386Y732520D03*
Y721890D03*
X233386Y732520D03*
Y721890D03*
X243386Y732520D03*
Y721890D03*
X223385Y896890D03*
X233385D03*
X243385D03*
X223385Y907520D03*
X233385D03*
X243385D03*
X223385Y1071890D03*
X233385D03*
X243385D03*
X223385Y1082520D03*
X233385D03*
X243385D03*
X223385Y1257520D03*
Y1246890D03*
X233385Y1257520D03*
Y1246890D03*
X243385Y1257520D03*
Y1246890D03*
X223385Y1432520D03*
Y1421890D03*
X233385Y1432520D03*
Y1421890D03*
X243385Y1432520D03*
Y1421890D03*
X223385Y1596890D03*
X233385D03*
X243385D03*
X223385Y1607520D03*
X233385D03*
X243385D03*
X223385Y1771890D03*
X233385D03*
X243385D03*
X223385Y1782520D03*
X233385D03*
X243385D03*
X223385Y1957520D03*
Y1946890D03*
X233385Y1957520D03*
Y1946890D03*
X243385Y1957520D03*
Y1946890D03*
X253385Y21890D03*
Y32520D03*
X263385Y21890D03*
Y32520D03*
X253385Y196890D03*
X263385D03*
X253385Y207520D03*
X263385D03*
X253385Y371890D03*
X263385D03*
X253385Y382520D03*
X263385D03*
X253386Y546890D03*
Y557520D03*
X263386Y546890D03*
Y557520D03*
X253386Y721890D03*
Y732520D03*
X263386Y721890D03*
Y732520D03*
X253385Y896890D03*
X263385D03*
X253385Y907520D03*
X263385D03*
X253385Y1071890D03*
X263385D03*
X253385Y1082520D03*
X263385D03*
X253385Y1246890D03*
Y1257520D03*
X263385Y1246890D03*
Y1257520D03*
X253385Y1421890D03*
Y1432520D03*
X263385Y1421890D03*
Y1432520D03*
X253385Y1596890D03*
X263385D03*
X253385Y1607520D03*
X263385D03*
X253385Y1771890D03*
X263385D03*
X253385Y1782520D03*
X263385D03*
X253385Y1946890D03*
Y1957520D03*
X263385Y1946890D03*
Y1957520D03*
X273385Y21890D03*
Y32520D03*
X283385Y21890D03*
Y32520D03*
X273385Y196890D03*
X283385D03*
X273385Y207520D03*
X283385D03*
X273385Y371890D03*
X283385D03*
X273385Y382520D03*
X283385D03*
X273386Y546890D03*
Y557520D03*
X283386Y546890D03*
Y557520D03*
X273386Y721890D03*
Y732520D03*
X283386Y721890D03*
Y732520D03*
X273385Y896890D03*
X283385D03*
X273385Y907520D03*
X283385D03*
X273385Y1071890D03*
X283385D03*
X273385Y1082520D03*
X283385D03*
X273385Y1246890D03*
Y1257520D03*
X283385Y1246890D03*
Y1257520D03*
X273385Y1421890D03*
Y1432520D03*
X283385Y1421890D03*
Y1432520D03*
X273385Y1596890D03*
X283385D03*
X273385Y1607520D03*
X283385D03*
X273385Y1771890D03*
X283385D03*
X273385Y1782520D03*
X283385D03*
X273385Y1946890D03*
Y1957520D03*
X283385Y1946890D03*
Y1957520D03*
X293385Y21890D03*
Y32520D03*
X303385Y21890D03*
Y32520D03*
X313385D03*
Y21890D03*
X293385Y196890D03*
X303385D03*
X313385D03*
X293385Y207520D03*
X303385D03*
X313385D03*
X293385Y371890D03*
X303385D03*
X313385D03*
X293385Y382520D03*
X303385D03*
X313385D03*
X293386Y546890D03*
Y557520D03*
X303386Y546890D03*
Y557520D03*
X313386D03*
Y546890D03*
X293386Y721890D03*
Y732520D03*
X303386Y721890D03*
Y732520D03*
X313386D03*
Y721890D03*
X293385Y896890D03*
X303385D03*
X313385D03*
X293385Y907520D03*
X303385D03*
X313385D03*
X293385Y1071890D03*
X303385D03*
X313385D03*
X293385Y1082520D03*
X303385D03*
X313385D03*
X293385Y1246890D03*
Y1257520D03*
X303385Y1246890D03*
Y1257520D03*
X313385D03*
Y1246890D03*
X293385Y1421890D03*
Y1432520D03*
X303385Y1421890D03*
Y1432520D03*
X313385D03*
Y1421890D03*
X293385Y1596890D03*
X303385D03*
X313385D03*
X293385Y1607520D03*
X303385D03*
X313385D03*
X293385Y1771890D03*
X303385D03*
X313385D03*
X293385Y1782520D03*
X303385D03*
X313385D03*
X293385Y1946890D03*
Y1957520D03*
X303385Y1946890D03*
Y1957520D03*
X313385D03*
Y1946890D03*
X337165Y24705D03*
X323385Y32520D03*
Y21890D03*
X337165Y34705D03*
Y199705D03*
X323385Y196890D03*
X337165Y209705D03*
X323385Y207520D03*
Y371890D03*
X337165Y374705D03*
Y384705D03*
X323385Y382520D03*
X337166Y549705D03*
Y559705D03*
X323386Y557520D03*
Y546890D03*
X337166Y724705D03*
X323386Y732520D03*
Y721890D03*
X337166Y734705D03*
X337165Y899705D03*
X323385Y896890D03*
X337165Y909705D03*
X323385Y907520D03*
Y1071890D03*
X337165Y1074705D03*
Y1084705D03*
X323385Y1082520D03*
X337165Y1249705D03*
Y1259705D03*
X323385Y1257520D03*
Y1246890D03*
X337165Y1424705D03*
Y1434705D03*
X323385Y1432520D03*
Y1421890D03*
X337165Y1599705D03*
X323385Y1596890D03*
X337165Y1609705D03*
X323385Y1607520D03*
Y1771890D03*
X337165Y1774705D03*
Y1784705D03*
X323385Y1782520D03*
X337165Y1949705D03*
Y1959705D03*
X323385Y1957520D03*
Y1946890D03*
X342165Y19705D03*
Y29705D03*
X347165Y24705D03*
X352165Y19705D03*
Y29705D03*
X357165Y24705D03*
X362165Y19705D03*
Y29705D03*
X347165Y34705D03*
X357165D03*
X342165Y194705D03*
X347165Y199705D03*
X352165Y194705D03*
X357165Y199705D03*
X362165Y194705D03*
X342165Y204705D03*
X347165Y209705D03*
X352165Y204705D03*
X357165Y209705D03*
X362165Y204705D03*
X342165Y369705D03*
X352165D03*
X362165D03*
X342165Y379705D03*
X347165Y374705D03*
Y384705D03*
X352165Y379705D03*
X357165Y374705D03*
Y384705D03*
X362165Y379705D03*
X342166Y544705D03*
Y554705D03*
X347166Y549705D03*
Y559705D03*
X352166Y544705D03*
Y554705D03*
X357166Y549705D03*
Y559705D03*
X362166Y544705D03*
Y554705D03*
X342166Y719705D03*
Y729705D03*
X347166Y724705D03*
X352166Y719705D03*
Y729705D03*
X357166Y724705D03*
X362166Y719705D03*
Y729705D03*
X347166Y734705D03*
X357166D03*
X342165Y894705D03*
X347165Y899705D03*
X352165Y894705D03*
X357165Y899705D03*
X362165Y894705D03*
X342165Y904705D03*
X347165Y909705D03*
X352165Y904705D03*
X357165Y909705D03*
X362165Y904705D03*
X342165Y1069705D03*
X352165D03*
X362165D03*
X342165Y1079705D03*
X347165Y1074705D03*
Y1084705D03*
X352165Y1079705D03*
X357165Y1074705D03*
Y1084705D03*
X362165Y1079705D03*
X342165Y1244705D03*
Y1254705D03*
X347165Y1249705D03*
Y1259705D03*
X352165Y1244705D03*
Y1254705D03*
X357165Y1249705D03*
Y1259705D03*
X362165Y1244705D03*
Y1254705D03*
X342165Y1419705D03*
Y1429705D03*
X347165Y1424705D03*
Y1434705D03*
X352165Y1419705D03*
Y1429705D03*
X357165Y1424705D03*
Y1434705D03*
X362165Y1419705D03*
Y1429705D03*
X342165Y1594705D03*
X347165Y1599705D03*
X352165Y1594705D03*
X357165Y1599705D03*
X362165Y1594705D03*
X342165Y1604705D03*
X347165Y1609705D03*
X352165Y1604705D03*
X357165Y1609705D03*
X362165Y1604705D03*
X342165Y1769705D03*
X352165D03*
X362165D03*
X342165Y1779705D03*
X347165Y1774705D03*
Y1784705D03*
X352165Y1779705D03*
X357165Y1774705D03*
Y1784705D03*
X362165Y1779705D03*
X342165Y1944705D03*
Y1954705D03*
X347165Y1949705D03*
Y1959705D03*
X352165Y1944705D03*
Y1954705D03*
X357165Y1949705D03*
Y1959705D03*
X362165Y1944705D03*
Y1954705D03*
M02*
